G04 ================== begin FILE IDENTIFICATION RECORD ==================*
G04 Layout Name:  13919-sa.brd*
G04 Film Name:    DP_REF_L4*
G04 File Format:  Gerber RS274X*
G04 File Origin:  Cadence Allegro 16.5-S039*
G04 Origin Date:  Fri Nov 22 15:27:08 2013*
G04 *
G04 Layer:  BOARD GEOMETRY/DP_REF_L4_TBL*
G04 Layer:  BOARD GEOMETRY/DP_REF_L4_BOTTOM*
G04 Layer:  BOARD GEOMETRY/PANEL_OUTLINE*
G04 *
G04 Offset:    (0.00 0.00)*
G04 Mirror:    No*
G04 Mode:      Positive*
G04 Rotation:  0*
G04 FullContactRelief:  No*
G04 UndefLineWidth:     6.00*
G04 ================== end FILE IDENTIFICATION RECORD ====================*
%FSLAX35Y35*MOIN*%
%IR0*IPPOS*OFA0.00000B0.00000*MIA0B0*SFA1.00000B1.00000*%
%ADD10C,.02*%
%ADD11C,.006*%
%ADD12C,.0055*%
G75*
%LPD*%
G75*
G54D10*
G01X825891Y587689D02*
X1350891D01*
G01X825891Y656989D02*
Y587689D01*
G01Y622339D02*
X1350891D01*
G01X825891Y656989D02*
X1350891D01*
G01X1000891D02*
Y587689D01*
G01X1245891Y656989D02*
Y587689D01*
G01X1350891Y656989D02*
Y587689D01*
G54D11*
G01X-14021Y-32800D02*
Y-50300D01*
G01X-19043Y-32800D02*
X-8999D01*
G01X-233Y-50300D02*
Y-32800D01*
G01Y-41258D02*
X859Y-39800D01*
X1951Y-38925D01*
X3697Y-38634D01*
X5007Y-38925D01*
X6536Y-40092D01*
X7191Y-41842D01*
Y-50300D01*
G01X20979Y-38634D02*
Y-50300D01*
G01Y-33967D02*
X20542Y-33675D01*
Y-33092D01*
X20979Y-32800D01*
X21416Y-33092D01*
Y-33675D01*
X20979Y-33967D01*
G01X35204Y-48259D02*
X36296Y-49425D01*
X37824Y-50300D01*
X39134D01*
X40444Y-49717D01*
X41317Y-48842D01*
X41754Y-47676D01*
X41536Y-45925D01*
X40662Y-45050D01*
X36732Y-43300D01*
X35859Y-41258D01*
X36296Y-39800D01*
X37169Y-38925D01*
X38479Y-38634D01*
X39789Y-38925D01*
X41099Y-39800D01*
G01X70422Y-54675D02*
X71951Y-55842D01*
X73697Y-56133D01*
X75225Y-55842D01*
X76536Y-54384D01*
X77409Y-52342D01*
Y-38634D01*
G01Y-40967D02*
X76536Y-39800D01*
X75225Y-38925D01*
X73697Y-38634D01*
X71951Y-39217D01*
X70859Y-40383D01*
X69985Y-42425D01*
X69549Y-44467D01*
X69767Y-46217D01*
X70641Y-48259D01*
X71951Y-49717D01*
X73697Y-50300D01*
X75007Y-50008D01*
X76536Y-48842D01*
X77409Y-47676D01*
G01X87704Y-42425D02*
X94691D01*
X94036Y-40383D01*
X92944Y-39217D01*
X91416Y-38634D01*
X89887Y-38925D01*
X88577Y-39800D01*
X87704Y-41842D01*
X87267Y-43592D01*
Y-45342D01*
X87704Y-47092D01*
X88796Y-48842D01*
X90106Y-50008D01*
X91634Y-50300D01*
X93162Y-49717D01*
X94691Y-47967D01*
G01X105422Y-50300D02*
Y-38634D01*
G01Y-40967D02*
X106514Y-39800D01*
X107606Y-38925D01*
X109134Y-38634D01*
X110225Y-38925D01*
X111536Y-39800D01*
G01X122049Y-50300D02*
Y-32800D01*
G01Y-41550D02*
X123141Y-39800D01*
X124451Y-38925D01*
X125761Y-38634D01*
X127725Y-39217D01*
X129036Y-40383D01*
X129909Y-42425D01*
Y-44758D01*
X129472Y-47092D01*
X128599Y-48842D01*
X127071Y-50008D01*
X125761Y-50300D01*
X124451Y-50008D01*
X123141Y-49134D01*
X122049Y-47676D01*
G01X140204Y-42425D02*
X147191D01*
X146536Y-40383D01*
X145444Y-39217D01*
X143916Y-38634D01*
X142387Y-38925D01*
X141077Y-39800D01*
X140204Y-41842D01*
X139767Y-43592D01*
Y-45342D01*
X140204Y-47092D01*
X141296Y-48842D01*
X142606Y-50008D01*
X144134Y-50300D01*
X145662Y-49717D01*
X147191Y-47967D01*
G01X157922Y-50300D02*
Y-38634D01*
G01Y-40967D02*
X159014Y-39800D01*
X160106Y-38925D01*
X161634Y-38634D01*
X162725Y-38925D01*
X164036Y-39800D01*
G01X195979Y-38634D02*
Y-50300D01*
G01Y-33967D02*
X195542Y-33675D01*
Y-33092D01*
X195979Y-32800D01*
X196416Y-33092D01*
Y-33675D01*
X195979Y-33967D01*
G01X210204Y-48259D02*
X211296Y-49425D01*
X212824Y-50300D01*
X214134D01*
X215444Y-49717D01*
X216317Y-48842D01*
X216754Y-47676D01*
X216536Y-45925D01*
X215662Y-45050D01*
X211732Y-43300D01*
X210859Y-41258D01*
X211296Y-39800D01*
X212169Y-38925D01*
X213479Y-38634D01*
X214789Y-38925D01*
X216099Y-39800D01*
G01X244985Y-54675D02*
X246514Y-55842D01*
X247824Y-56133D01*
X249571Y-55550D01*
X250881Y-54092D01*
X251536Y-51466D01*
Y-38634D01*
G01Y-33967D02*
X251099Y-33675D01*
Y-33092D01*
X251536Y-32800D01*
X251972Y-33092D01*
Y-33675D01*
X251536Y-33967D01*
G01X262267Y-38634D02*
Y-46800D01*
X263141Y-48842D01*
X264451Y-50008D01*
X265979Y-50300D01*
X267507Y-50008D01*
X268817Y-48842D01*
X269691Y-46800D01*
G01Y-50300D02*
Y-38634D01*
G01X280204Y-48259D02*
X281296Y-49425D01*
X282824Y-50300D01*
X284134D01*
X285444Y-49717D01*
X286317Y-48842D01*
X286754Y-47676D01*
X286536Y-45925D01*
X285662Y-45050D01*
X281732Y-43300D01*
X280859Y-41258D01*
X281296Y-39800D01*
X282169Y-38925D01*
X283479Y-38634D01*
X284789Y-38925D01*
X286099Y-39800D01*
G01X300979Y-32800D02*
Y-50300D01*
G01X297922Y-38634D02*
X304036D01*
G01X334669Y-50300D02*
Y-35425D01*
X335106Y-33967D01*
X335979Y-33092D01*
X337289Y-32800D01*
X338599Y-33383D01*
X339254Y-34842D01*
G01X336634Y-39800D02*
X332267D01*
G01X353479Y-50300D02*
X352169Y-50008D01*
X350859Y-48842D01*
X349985Y-46800D01*
X349549Y-44467D01*
X349985Y-42133D01*
X350859Y-40092D01*
X352169Y-38925D01*
X353479Y-38634D01*
X354789Y-38925D01*
X356099Y-40092D01*
X356972Y-42133D01*
X357191Y-44467D01*
X356972Y-46800D01*
X356099Y-48842D01*
X354789Y-50008D01*
X353479Y-50300D01*
G01X367922D02*
Y-38634D01*
G01Y-40967D02*
X369014Y-39800D01*
X370106Y-38925D01*
X371634Y-38634D01*
X372725Y-38925D01*
X374036Y-39800D01*
G01X401394Y-55550D02*
X402704Y-56133D01*
X404451Y-55550D01*
X405542Y-54384D01*
X406416Y-52925D01*
X407725Y-48259D01*
X410564Y-38634D01*
G01X403577D02*
X407725Y-48259D01*
G01X423479Y-50300D02*
X422169Y-50008D01*
X420859Y-48842D01*
X419985Y-46800D01*
X419549Y-44467D01*
X419985Y-42133D01*
X420859Y-40092D01*
X422169Y-38925D01*
X423479Y-38634D01*
X424789Y-38925D01*
X426099Y-40092D01*
X426972Y-42133D01*
X427191Y-44467D01*
X426972Y-46800D01*
X426099Y-48842D01*
X424789Y-50008D01*
X423479Y-50300D01*
G01X437267Y-38634D02*
Y-46800D01*
X438141Y-48842D01*
X439451Y-50008D01*
X440979Y-50300D01*
X442507Y-50008D01*
X443817Y-48842D01*
X444691Y-46800D01*
G01Y-50300D02*
Y-38634D01*
G01X455422Y-50300D02*
Y-38634D01*
G01Y-40967D02*
X456514Y-39800D01*
X457606Y-38925D01*
X459134Y-38634D01*
X460225Y-38925D01*
X461536Y-39800D01*
G01X490422Y-50300D02*
Y-38634D01*
G01Y-40967D02*
X491514Y-39800D01*
X492606Y-38925D01*
X494134Y-38634D01*
X495225Y-38925D01*
X496536Y-39800D01*
G01X507704Y-42425D02*
X514691D01*
X514036Y-40383D01*
X512944Y-39217D01*
X511416Y-38634D01*
X509887Y-38925D01*
X508577Y-39800D01*
X507704Y-41842D01*
X507267Y-43592D01*
Y-45342D01*
X507704Y-47092D01*
X508796Y-48842D01*
X510106Y-50008D01*
X511634Y-50300D01*
X513162Y-49717D01*
X514691Y-47967D01*
G01X527169Y-50300D02*
Y-35425D01*
X527606Y-33967D01*
X528479Y-33092D01*
X529789Y-32800D01*
X531099Y-33383D01*
X531754Y-34842D01*
G01X529134Y-39800D02*
X524767D01*
G01X542704Y-42425D02*
X549691D01*
X549036Y-40383D01*
X547944Y-39217D01*
X546416Y-38634D01*
X544887Y-38925D01*
X543577Y-39800D01*
X542704Y-41842D01*
X542267Y-43592D01*
Y-45342D01*
X542704Y-47092D01*
X543796Y-48842D01*
X545106Y-50008D01*
X546634Y-50300D01*
X548162Y-49717D01*
X549691Y-47967D01*
G01X560422Y-50300D02*
Y-38634D01*
G01Y-40967D02*
X561514Y-39800D01*
X562606Y-38925D01*
X564134Y-38634D01*
X565225Y-38925D01*
X566536Y-39800D01*
G01X577704Y-42425D02*
X584691D01*
X584036Y-40383D01*
X582944Y-39217D01*
X581416Y-38634D01*
X579887Y-38925D01*
X578577Y-39800D01*
X577704Y-41842D01*
X577267Y-43592D01*
Y-45342D01*
X577704Y-47092D01*
X578796Y-48842D01*
X580106Y-50008D01*
X581634Y-50300D01*
X583162Y-49717D01*
X584691Y-47967D01*
G01X594767Y-50300D02*
Y-38634D01*
G01Y-41550D02*
X595641Y-40092D01*
X596951Y-38925D01*
X598697Y-38634D01*
X600225Y-38925D01*
X601536Y-40092D01*
X602191Y-42133D01*
Y-50300D01*
G01X619472Y-40092D02*
X617944Y-38925D01*
X616634Y-38634D01*
X614887Y-39217D01*
X613577Y-40383D01*
X612704Y-42425D01*
X612485Y-44467D01*
X612704Y-46509D01*
X613577Y-48259D01*
X614887Y-49717D01*
X616634Y-50300D01*
X618162Y-49717D01*
X619472Y-48550D01*
G01X630204Y-42425D02*
X637191D01*
X636536Y-40383D01*
X635444Y-39217D01*
X633916Y-38634D01*
X632387Y-38925D01*
X631077Y-39800D01*
X630204Y-41842D01*
X629767Y-43592D01*
Y-45342D01*
X630204Y-47092D01*
X631296Y-48842D01*
X632606Y-50008D01*
X634134Y-50300D01*
X635662Y-49717D01*
X637191Y-47967D01*
G01X668479Y-32800D02*
Y-50300D01*
G01X665422Y-38634D02*
X671536D01*
G01X685979Y-50300D02*
X684669Y-50008D01*
X683359Y-48842D01*
X682485Y-46800D01*
X682049Y-44467D01*
X682485Y-42133D01*
X683359Y-40092D01*
X684669Y-38925D01*
X685979Y-38634D01*
X687289Y-38925D01*
X688599Y-40092D01*
X689472Y-42133D01*
X689691Y-44467D01*
X689472Y-46800D01*
X688599Y-48842D01*
X687289Y-50008D01*
X685979Y-50300D01*
G01X719669D02*
Y-35425D01*
X720106Y-33967D01*
X720979Y-33092D01*
X722289Y-32800D01*
X723599Y-33383D01*
X724254Y-34842D01*
G01X721634Y-39800D02*
X717267D01*
G01X738479Y-38634D02*
Y-50300D01*
G01Y-33967D02*
X738042Y-33675D01*
Y-33092D01*
X738479Y-32800D01*
X738916Y-33092D01*
Y-33675D01*
X738479Y-33967D01*
G01X752267Y-50300D02*
Y-38634D01*
G01Y-41550D02*
X753141Y-40092D01*
X754451Y-38925D01*
X756197Y-38634D01*
X757725Y-38925D01*
X759036Y-40092D01*
X759691Y-42133D01*
Y-50300D01*
G01X777409Y-32800D02*
Y-50300D01*
G01Y-47676D02*
X776536Y-49134D01*
X775225Y-50008D01*
X773697Y-50300D01*
X771951Y-49717D01*
X770641Y-48259D01*
X769767Y-46509D01*
X769549Y-44467D01*
X769767Y-42425D01*
X770641Y-40675D01*
X771951Y-39217D01*
X773697Y-38634D01*
X775225Y-38925D01*
X776317Y-39509D01*
X777409Y-40675D01*
G01X808479Y-32800D02*
Y-50300D01*
G01X805422Y-38634D02*
X811536D01*
G01X822267Y-50300D02*
Y-32800D01*
G01Y-41258D02*
X823359Y-39800D01*
X824451Y-38925D01*
X826197Y-38634D01*
X827507Y-38925D01*
X829036Y-40092D01*
X829691Y-41842D01*
Y-50300D01*
G01X840204Y-42425D02*
X847191D01*
X846536Y-40383D01*
X845444Y-39217D01*
X843916Y-38634D01*
X842387Y-38925D01*
X841077Y-39800D01*
X840204Y-41842D01*
X839767Y-43592D01*
Y-45342D01*
X840204Y-47092D01*
X841296Y-48842D01*
X842606Y-50008D01*
X844134Y-50300D01*
X845662Y-49717D01*
X847191Y-47967D01*
G01X873676Y-50300D02*
Y-32800D01*
X878042D01*
X879789Y-33675D01*
X881099Y-34842D01*
X882191Y-36591D01*
X883064Y-38634D01*
X883282Y-41550D01*
X883064Y-44467D01*
X882191Y-46509D01*
X881099Y-48259D01*
X879789Y-49425D01*
X878042Y-50300D01*
X873676D01*
G01X891612D02*
Y-32800D01*
X896852D01*
X898599Y-33675D01*
X899909Y-35717D01*
X900346Y-38050D01*
X899909Y-40383D01*
X898817Y-42133D01*
X896852Y-43009D01*
X891612D01*
G01X930979Y-38634D02*
Y-50300D01*
G01Y-33967D02*
X930542Y-33675D01*
Y-33092D01*
X930979Y-32800D01*
X931416Y-33092D01*
Y-33675D01*
X930979Y-33967D01*
G01X941929Y-50300D02*
Y-38634D01*
G01Y-41842D02*
X942584Y-40383D01*
X943676Y-39217D01*
X945204Y-38634D01*
X946732Y-39217D01*
X947824Y-40383D01*
X948479Y-41842D01*
Y-50300D01*
G01Y-41842D02*
X949134Y-40383D01*
X950225Y-39217D01*
X951754Y-38634D01*
X953282Y-39217D01*
X954374Y-40383D01*
X955029Y-42133D01*
Y-50300D01*
G01X962049Y-56133D02*
Y-38634D01*
G01Y-41258D02*
X963141Y-39800D01*
X964232Y-38925D01*
X965979Y-38634D01*
X967507Y-38925D01*
X969036Y-40383D01*
X969691Y-42425D01*
X969909Y-44467D01*
X969691Y-46509D01*
X969036Y-48550D01*
X967725Y-49717D01*
X965979Y-50300D01*
X964451Y-50008D01*
X962922Y-49134D01*
X962049Y-47967D01*
G01X980204Y-42425D02*
X987191D01*
X986536Y-40383D01*
X985444Y-39217D01*
X983916Y-38634D01*
X982387Y-38925D01*
X981077Y-39800D01*
X980204Y-41842D01*
X979767Y-43592D01*
Y-45342D01*
X980204Y-47092D01*
X981296Y-48842D01*
X982606Y-50008D01*
X984134Y-50300D01*
X985662Y-49717D01*
X987191Y-47967D01*
G01X1004909Y-32800D02*
Y-50300D01*
G01Y-47676D02*
X1004036Y-49134D01*
X1002725Y-50008D01*
X1001197Y-50300D01*
X999451Y-49717D01*
X998141Y-48259D01*
X997267Y-46509D01*
X997049Y-44467D01*
X997267Y-42425D01*
X998141Y-40675D01*
X999451Y-39217D01*
X1001197Y-38634D01*
X1002725Y-38925D01*
X1003817Y-39509D01*
X1004909Y-40675D01*
G01X1022409Y-50300D02*
Y-38634D01*
G01Y-40675D02*
X1021536Y-39509D01*
X1020225Y-38925D01*
X1018697Y-38634D01*
X1017169Y-39217D01*
X1015859Y-40383D01*
X1014985Y-42133D01*
X1014549Y-44467D01*
X1014985Y-46800D01*
X1015859Y-48550D01*
X1017169Y-49717D01*
X1018697Y-50300D01*
X1020225Y-50008D01*
X1021536Y-49134D01*
X1022409Y-47967D01*
G01X1032267Y-50300D02*
Y-38634D01*
G01Y-41550D02*
X1033141Y-40092D01*
X1034451Y-38925D01*
X1036197Y-38634D01*
X1037725Y-38925D01*
X1039036Y-40092D01*
X1039691Y-42133D01*
Y-50300D01*
G01X1056972Y-40092D02*
X1055444Y-38925D01*
X1054134Y-38634D01*
X1052387Y-39217D01*
X1051077Y-40383D01*
X1050204Y-42425D01*
X1049985Y-44467D01*
X1050204Y-46509D01*
X1051077Y-48259D01*
X1052387Y-49717D01*
X1054134Y-50300D01*
X1055662Y-49717D01*
X1056972Y-48550D01*
G01X1067704Y-42425D02*
X1074691D01*
X1074036Y-40383D01*
X1072944Y-39217D01*
X1071416Y-38634D01*
X1069887Y-38925D01*
X1068577Y-39800D01*
X1067704Y-41842D01*
X1067267Y-43592D01*
Y-45342D01*
X1067704Y-47092D01*
X1068796Y-48842D01*
X1070106Y-50008D01*
X1071634Y-50300D01*
X1073162Y-49717D01*
X1074691Y-47967D01*
G01X1105979Y-32800D02*
Y-50300D01*
G01X1102922Y-38634D02*
X1109036D01*
G01X1120422Y-50300D02*
Y-38634D01*
G01Y-40967D02*
X1121514Y-39800D01*
X1122606Y-38925D01*
X1124134Y-38634D01*
X1125225Y-38925D01*
X1126536Y-39800D01*
G01X1144909Y-50300D02*
Y-38634D01*
G01Y-40675D02*
X1144036Y-39509D01*
X1142725Y-38925D01*
X1141197Y-38634D01*
X1139669Y-39217D01*
X1138359Y-40383D01*
X1137485Y-42133D01*
X1137049Y-44467D01*
X1137485Y-46800D01*
X1138359Y-48550D01*
X1139669Y-49717D01*
X1141197Y-50300D01*
X1142725Y-50008D01*
X1144036Y-49134D01*
X1144909Y-47967D01*
G01X1161972Y-40092D02*
X1160444Y-38925D01*
X1159134Y-38634D01*
X1157387Y-39217D01*
X1156077Y-40383D01*
X1155204Y-42425D01*
X1154985Y-44467D01*
X1155204Y-46509D01*
X1156077Y-48259D01*
X1157387Y-49717D01*
X1159134Y-50300D01*
X1160662Y-49717D01*
X1161972Y-48550D01*
G01X1172704Y-42425D02*
X1179691D01*
X1179036Y-40383D01*
X1177944Y-39217D01*
X1176416Y-38634D01*
X1174887Y-38925D01*
X1173577Y-39800D01*
X1172704Y-41842D01*
X1172267Y-43592D01*
Y-45342D01*
X1172704Y-47092D01*
X1173796Y-48842D01*
X1175106Y-50008D01*
X1176634Y-50300D01*
X1178162Y-49717D01*
X1179691Y-47967D01*
G01X1190204Y-48259D02*
X1191296Y-49425D01*
X1192824Y-50300D01*
X1194134D01*
X1195444Y-49717D01*
X1196317Y-48842D01*
X1196754Y-47676D01*
X1196536Y-45925D01*
X1195662Y-45050D01*
X1191732Y-43300D01*
X1190859Y-41258D01*
X1191296Y-39800D01*
X1192169Y-38925D01*
X1193479Y-38634D01*
X1194789Y-38925D01*
X1196099Y-39800D01*
G01X1228479Y-38634D02*
Y-50300D01*
G01Y-33967D02*
X1228042Y-33675D01*
Y-33092D01*
X1228479Y-32800D01*
X1228916Y-33092D01*
Y-33675D01*
X1228479Y-33967D01*
G01X1242267Y-50300D02*
Y-38634D01*
G01Y-41550D02*
X1243141Y-40092D01*
X1244451Y-38925D01*
X1246197Y-38634D01*
X1247725Y-38925D01*
X1249036Y-40092D01*
X1249691Y-42133D01*
Y-50300D01*
G01X1280979D02*
Y-32800D01*
G01X1302409Y-50300D02*
Y-38634D01*
G01Y-40675D02*
X1301536Y-39509D01*
X1300225Y-38925D01*
X1298697Y-38634D01*
X1297169Y-39217D01*
X1295859Y-40383D01*
X1294985Y-42133D01*
X1294549Y-44467D01*
X1294985Y-46800D01*
X1295859Y-48550D01*
X1297169Y-49717D01*
X1298697Y-50300D01*
X1300225Y-50008D01*
X1301536Y-49134D01*
X1302409Y-47967D01*
G01X1311394Y-55550D02*
X1312704Y-56133D01*
X1314451Y-55550D01*
X1315542Y-54384D01*
X1316416Y-52925D01*
X1317725Y-48259D01*
X1320564Y-38634D01*
G01X1313577D02*
X1317725Y-48259D01*
G01X1330204Y-42425D02*
X1337191D01*
X1336536Y-40383D01*
X1335444Y-39217D01*
X1333916Y-38634D01*
X1332387Y-38925D01*
X1331077Y-39800D01*
X1330204Y-41842D01*
X1329767Y-43592D01*
Y-45342D01*
X1330204Y-47092D01*
X1331296Y-48842D01*
X1332606Y-50008D01*
X1334134Y-50300D01*
X1335662Y-49717D01*
X1337191Y-47967D01*
G01X1347922Y-50300D02*
Y-38634D01*
G01Y-40967D02*
X1349014Y-39800D01*
X1350106Y-38925D01*
X1351634Y-38634D01*
X1352725Y-38925D01*
X1354036Y-39800D01*
G01X1381612Y-32800D02*
Y-50300D01*
X1390346D01*
G01X1406099D02*
Y-32800D01*
X1398020Y-45342D01*
X1408938D01*
G01X1420979Y-50883D02*
X1420542Y-50592D01*
Y-50008D01*
X1420979Y-49717D01*
X1421416Y-50008D01*
Y-50592D01*
X1420979Y-50883D01*
G01X827638Y666739D02*
Y684239D01*
X832004D01*
X833751Y683364D01*
X835061Y682197D01*
X836153Y680448D01*
X837026Y678405D01*
X837244Y675489D01*
X837026Y672572D01*
X836153Y670530D01*
X835061Y668780D01*
X833751Y667614D01*
X832004Y666739D01*
X827638D01*
G01X845574D02*
Y684239D01*
X850814D01*
X852561Y683364D01*
X853871Y681322D01*
X854308Y678989D01*
X853871Y676656D01*
X852779Y674906D01*
X850814Y674030D01*
X845574D01*
G01X882321Y684239D02*
X887561D01*
G01X884941D02*
Y666739D01*
G01X882321D02*
X887561D01*
G01X896764D02*
Y684239D01*
X902441Y669656D01*
X908118Y684239D01*
Y666739D01*
G01X915574D02*
Y684239D01*
X920814D01*
X922561Y683364D01*
X923871Y681322D01*
X924308Y678989D01*
X923871Y676656D01*
X922779Y674906D01*
X920814Y674030D01*
X915574D01*
G01X941808Y666739D02*
X933074D01*
Y684239D01*
X941808D01*
G01X938314Y675781D02*
X933074D01*
G01X950138Y666739D02*
Y684239D01*
X954504D01*
X956251Y683364D01*
X957561Y682197D01*
X958653Y680448D01*
X959526Y678405D01*
X959744Y675489D01*
X959526Y672572D01*
X958653Y670530D01*
X957561Y668780D01*
X956251Y667614D01*
X954504Y666739D01*
X950138D01*
G01X966982D02*
X972441Y684239D01*
X977900Y666739D01*
G01X975934Y672864D02*
X968947D01*
G01X984919Y666739D02*
Y684239D01*
X994963Y666739D01*
Y684239D01*
G01X1012244Y682780D02*
X1010934Y683656D01*
X1009406Y684239D01*
X1007659D01*
X1005694Y683364D01*
X1004166Y681906D01*
X1003074Y680155D01*
X1002201Y677239D01*
X1001982Y674614D01*
X1002419Y671989D01*
X1003074Y670239D01*
X1004384Y668489D01*
X1005913Y667322D01*
X1007441Y666739D01*
X1008969D01*
X1010498Y667322D01*
X1011808Y668197D01*
X1012900Y669363D01*
G01X1029308Y666739D02*
X1020574D01*
Y684239D01*
X1029308D01*
G01X1025814Y675781D02*
X1020574D01*
G01X1059941Y684239D02*
Y666739D01*
G01X1054919Y684239D02*
X1064963D01*
G01X1071982Y666739D02*
X1077441Y684239D01*
X1082900Y666739D01*
G01X1080934Y672864D02*
X1073947D01*
G01X1096687Y676072D02*
X1097561Y676947D01*
X1098216Y678405D01*
X1098653Y680448D01*
X1098216Y682197D01*
X1097343Y683364D01*
X1095814Y684239D01*
X1089919D01*
Y666739D01*
X1097124D01*
X1098653Y667905D01*
X1099526Y669656D01*
X1099963Y671697D01*
X1099526Y673739D01*
X1098216Y675489D01*
X1096687Y676072D01*
X1089919D01*
G01X1108074Y684239D02*
Y666739D01*
X1116808D01*
G01X1134308D02*
X1125574D01*
Y684239D01*
X1134308D01*
G01X1130814Y675781D02*
X1125574D01*
G01X1147441Y666156D02*
X1147004Y666447D01*
Y667031D01*
X1147441Y667322D01*
X1147878Y667031D01*
Y666447D01*
X1147441Y666156D01*
G01Y674030D02*
X1147004Y674322D01*
Y674906D01*
X1147441Y675197D01*
X1147878Y674906D01*
Y674322D01*
X1147441Y674030D01*
G01X1178074Y684239D02*
Y666739D01*
X1186808D01*
G01X1202561D02*
Y684239D01*
X1194482Y671697D01*
X1205400D01*
G01X849521Y649589D02*
X854761D01*
G01X852141D02*
Y632089D01*
G01X849521D02*
X854761D01*
G01X863964D02*
Y649589D01*
X869641Y635006D01*
X875318Y649589D01*
Y632089D01*
G01X882774D02*
Y649589D01*
X888014D01*
X889761Y648714D01*
X891071Y646672D01*
X891508Y644339D01*
X891071Y642006D01*
X889979Y640256D01*
X888014Y639380D01*
X882774D01*
G01X903549Y626256D02*
X901366Y629172D01*
X900274Y632089D01*
Y643755D01*
X901366Y646672D01*
X903549Y649589D01*
G01X922141Y632089D02*
X920394Y632381D01*
X918866Y633547D01*
X917556Y635297D01*
X916682Y637339D01*
X916246Y639672D01*
Y642006D01*
X916682Y644339D01*
X917556Y646381D01*
X918866Y648130D01*
X920394Y649297D01*
X922141Y649589D01*
X923887Y649297D01*
X925416Y648130D01*
X926726Y646381D01*
X927600Y644339D01*
X928036Y642006D01*
Y639672D01*
X927600Y637339D01*
X926726Y635297D01*
X925416Y633547D01*
X923887Y632381D01*
X922141Y632089D01*
G01X935929D02*
Y649589D01*
G01Y641131D02*
X937021Y642589D01*
X938113Y643464D01*
X939859Y643755D01*
X941169Y643464D01*
X942698Y642297D01*
X943353Y640547D01*
Y632089D01*
G01X950591D02*
Y643755D01*
G01Y640547D02*
X951246Y642006D01*
X952338Y643172D01*
X953866Y643755D01*
X955394Y643172D01*
X956486Y642006D01*
X957141Y640547D01*
Y632089D01*
G01Y640547D02*
X957796Y642006D01*
X958887Y643172D01*
X960416Y643755D01*
X961944Y643172D01*
X963036Y642006D01*
X963691Y640256D01*
Y632089D01*
G01X975733Y626256D02*
X977916Y629172D01*
X979008Y632089D01*
Y643755D01*
X977916Y646672D01*
X975733Y649589D01*
G01X887141Y597439D02*
X888669Y597731D01*
X890416Y598605D01*
X891508Y600063D01*
X891944Y602106D01*
X891508Y604147D01*
X890198Y605897D01*
X888233Y606772D01*
X886049D01*
X884739Y607356D01*
X883647Y608814D01*
X883211Y610855D01*
X883866Y612897D01*
X885394Y614356D01*
X887141Y614939D01*
X888887Y614356D01*
X890416Y612897D01*
X891071Y610855D01*
X890634Y608814D01*
X889543Y607356D01*
X888233Y606772D01*
X886049D01*
X884084Y605897D01*
X882774Y604147D01*
X882338Y602106D01*
X882774Y600063D01*
X883866Y598605D01*
X885613Y597731D01*
X887141Y597439D01*
G01X899838Y600063D02*
X901147Y598605D01*
X902676Y597731D01*
X904641Y597439D01*
X906606Y598022D01*
X908134Y599189D01*
X909226Y601230D01*
X909444Y603564D01*
X909008Y605897D01*
X907916Y607356D01*
X906387Y608522D01*
X904859Y608814D01*
X903331Y608522D01*
X901366Y607356D01*
X902021Y614939D01*
X907916D01*
G01X922141Y596856D02*
X921704Y597147D01*
Y597731D01*
X922141Y598022D01*
X922578Y597731D01*
Y597147D01*
X922141Y596856D01*
G01X939641Y614939D02*
X937894Y614356D01*
X936584Y612897D01*
X935711Y611148D01*
X935056Y608814D01*
X934838Y606189D01*
X935056Y603564D01*
X935711Y601230D01*
X936584Y599480D01*
X937894Y598022D01*
X939641Y597439D01*
X941387Y598022D01*
X942698Y599480D01*
X943571Y601230D01*
X944226Y603564D01*
X944444Y606189D01*
X944226Y608814D01*
X943571Y611148D01*
X942698Y612897D01*
X941387Y614356D01*
X939641Y614939D01*
G01X1029341Y649589D02*
X1032397Y632089D01*
X1035891Y649589D01*
X1039384Y632089D01*
X1042441Y649589D01*
G01X1050771D02*
X1056011D01*
G01X1053391D02*
Y632089D01*
G01X1050771D02*
X1056011D01*
G01X1066088D02*
Y649589D01*
X1070454D01*
X1072201Y648714D01*
X1073511Y647547D01*
X1074603Y645798D01*
X1075476Y643755D01*
X1075694Y640839D01*
X1075476Y637922D01*
X1074603Y635880D01*
X1073511Y634130D01*
X1072201Y632964D01*
X1070454Y632089D01*
X1066088D01*
G01X1088391Y649589D02*
Y632089D01*
G01X1083369Y649589D02*
X1093413D01*
G01X1101306Y632089D02*
Y649589D01*
G01X1110476D02*
Y632089D01*
G01Y640839D02*
X1101306D01*
G01X1122299Y626256D02*
X1120116Y629172D01*
X1119024Y632089D01*
Y643755D01*
X1120116Y646672D01*
X1122299Y649589D01*
G01X1134341Y632089D02*
Y643755D01*
G01Y640547D02*
X1134996Y642006D01*
X1136088Y643172D01*
X1137616Y643755D01*
X1139144Y643172D01*
X1140236Y642006D01*
X1140891Y640547D01*
Y632089D01*
G01Y640547D02*
X1141546Y642006D01*
X1142637Y643172D01*
X1144166Y643755D01*
X1145694Y643172D01*
X1146786Y642006D01*
X1147441Y640256D01*
Y632089D01*
G01X1158391Y643755D02*
Y632089D01*
G01Y648422D02*
X1157954Y648714D01*
Y649297D01*
X1158391Y649589D01*
X1158828Y649297D01*
Y648714D01*
X1158391Y648422D01*
G01X1175891Y632089D02*
Y649589D01*
G01X1190116Y634130D02*
X1191208Y632964D01*
X1192736Y632089D01*
X1194046D01*
X1195356Y632672D01*
X1196229Y633547D01*
X1196666Y634713D01*
X1196448Y636464D01*
X1195574Y637339D01*
X1191644Y639089D01*
X1190771Y641131D01*
X1191208Y642589D01*
X1192081Y643464D01*
X1193391Y643755D01*
X1194701Y643464D01*
X1196011Y642589D01*
G01X1211983Y626256D02*
X1214166Y629172D01*
X1215258Y632089D01*
Y643755D01*
X1214166Y646672D01*
X1211983Y649589D01*
G01X1066088Y600063D02*
X1067397Y598605D01*
X1068926Y597731D01*
X1070891Y597439D01*
X1072856Y598022D01*
X1074384Y599189D01*
X1075476Y601230D01*
X1075694Y603564D01*
X1075258Y605897D01*
X1074166Y607356D01*
X1072637Y608522D01*
X1071109Y608814D01*
X1069581Y608522D01*
X1067616Y607356D01*
X1068271Y614939D01*
X1074166D01*
G01X1088391Y596856D02*
X1087954Y597147D01*
Y597731D01*
X1088391Y598022D01*
X1088828Y597731D01*
Y597147D01*
X1088391Y596856D01*
G01X1101088Y600063D02*
X1102397Y598605D01*
X1103926Y597731D01*
X1105891Y597439D01*
X1107856Y598022D01*
X1109384Y599189D01*
X1110476Y601230D01*
X1110694Y603564D01*
X1110258Y605897D01*
X1109166Y607356D01*
X1107637Y608522D01*
X1106109Y608814D01*
X1104581Y608522D01*
X1102616Y607356D01*
X1103271Y614939D01*
X1109166D01*
G01X1119461Y596856D02*
X1127321Y614939D01*
G01X1140891Y597439D02*
X1142419Y597731D01*
X1144166Y598605D01*
X1145258Y600063D01*
X1145694Y602106D01*
X1145258Y604147D01*
X1143948Y605897D01*
X1141983Y606772D01*
X1139799D01*
X1138489Y607356D01*
X1137397Y608814D01*
X1136961Y610855D01*
X1137616Y612897D01*
X1139144Y614356D01*
X1140891Y614939D01*
X1142637Y614356D01*
X1144166Y612897D01*
X1144821Y610855D01*
X1144384Y608814D01*
X1143293Y607356D01*
X1141983Y606772D01*
X1139799D01*
X1137834Y605897D01*
X1136524Y604147D01*
X1136088Y602106D01*
X1136524Y600063D01*
X1137616Y598605D01*
X1139363Y597731D01*
X1140891Y597439D01*
G01X1158391Y596856D02*
X1157954Y597147D01*
Y597731D01*
X1158391Y598022D01*
X1158828Y597731D01*
Y597147D01*
X1158391Y596856D01*
G01X1175891Y614939D02*
X1174144Y614356D01*
X1172834Y612897D01*
X1171961Y611148D01*
X1171306Y608814D01*
X1171088Y606189D01*
X1171306Y603564D01*
X1171961Y601230D01*
X1172834Y599480D01*
X1174144Y598022D01*
X1175891Y597439D01*
X1177637Y598022D01*
X1178948Y599480D01*
X1179821Y601230D01*
X1180476Y603564D01*
X1180694Y606189D01*
X1180476Y608814D01*
X1179821Y611148D01*
X1178948Y612897D01*
X1177637Y614356D01*
X1175891Y614939D01*
G01X1272141Y649589D02*
Y632089D01*
G01X1267119Y649589D02*
X1277163D01*
G01X1289641Y632089D02*
Y639964D01*
X1285274Y649589D01*
G01X1294008D02*
X1289641Y639964D01*
G01X1302774Y632089D02*
Y649589D01*
X1308014D01*
X1309761Y648714D01*
X1311071Y646672D01*
X1311508Y644339D01*
X1311071Y642006D01*
X1309979Y640256D01*
X1308014Y639380D01*
X1302774D01*
G01X1329008Y632089D02*
X1320274D01*
Y649589D01*
X1329008D01*
G01X1325514Y641131D02*
X1320274D01*
G01X1284838Y597439D02*
Y614939D01*
X1289204D01*
X1290951Y614064D01*
X1292261Y612897D01*
X1293353Y611148D01*
X1294226Y609105D01*
X1294444Y606189D01*
X1294226Y603272D01*
X1293353Y601230D01*
X1292261Y599480D01*
X1290951Y598314D01*
X1289204Y597439D01*
X1284838D01*
G01X1302774D02*
Y614939D01*
X1308014D01*
X1309761Y614064D01*
X1311071Y612022D01*
X1311508Y609689D01*
X1311071Y607356D01*
X1309979Y605606D01*
X1308014Y604730D01*
X1302774D01*
G01X1477441Y574455D02*
Y562789D01*
G01Y579122D02*
X1477004Y579414D01*
Y579997D01*
X1477441Y580289D01*
X1477878Y579997D01*
Y579414D01*
X1477441Y579122D01*
G01X1491229Y562789D02*
Y574455D01*
G01Y571539D02*
X1492103Y572997D01*
X1493413Y574164D01*
X1495159Y574455D01*
X1496687Y574164D01*
X1497998Y572997D01*
X1498653Y570956D01*
Y562789D01*
G01X1509166Y564830D02*
X1510258Y563664D01*
X1511786Y562789D01*
X1513096D01*
X1514406Y563372D01*
X1515279Y564247D01*
X1515716Y565413D01*
X1515498Y567164D01*
X1514624Y568039D01*
X1510694Y569789D01*
X1509821Y571831D01*
X1510258Y573289D01*
X1511131Y574164D01*
X1512441Y574455D01*
X1513751Y574164D01*
X1515061Y573289D01*
G01X1529941Y574455D02*
Y562789D01*
G01Y579122D02*
X1529504Y579414D01*
Y579997D01*
X1529941Y580289D01*
X1530378Y579997D01*
Y579414D01*
X1529941Y579122D01*
G01X1551371Y580289D02*
Y562789D01*
G01Y565413D02*
X1550498Y563955D01*
X1549187Y563081D01*
X1547659Y562789D01*
X1545913Y563372D01*
X1544603Y564830D01*
X1543729Y566580D01*
X1543511Y568622D01*
X1543729Y570664D01*
X1544603Y572414D01*
X1545913Y573872D01*
X1547659Y574455D01*
X1549187Y574164D01*
X1550279Y573580D01*
X1551371Y572414D01*
G01X1561666Y570664D02*
X1568653D01*
X1567998Y572706D01*
X1566906Y573872D01*
X1565378Y574455D01*
X1563849Y574164D01*
X1562539Y573289D01*
X1561666Y571247D01*
X1561229Y569497D01*
Y567747D01*
X1561666Y565997D01*
X1562758Y564247D01*
X1564068Y563081D01*
X1565596Y562789D01*
X1567124Y563372D01*
X1568653Y565122D01*
G01X1596011Y562789D02*
Y580289D01*
G01Y571539D02*
X1597103Y573289D01*
X1598413Y574164D01*
X1599723Y574455D01*
X1601687Y573872D01*
X1602998Y572706D01*
X1603871Y570664D01*
Y568331D01*
X1603434Y565997D01*
X1602561Y564247D01*
X1601033Y563081D01*
X1599723Y562789D01*
X1598413Y563081D01*
X1597103Y563955D01*
X1596011Y565413D01*
G01X1617441Y562789D02*
X1616131Y563081D01*
X1614821Y564247D01*
X1613947Y566289D01*
X1613511Y568622D01*
X1613947Y570956D01*
X1614821Y572997D01*
X1616131Y574164D01*
X1617441Y574455D01*
X1618751Y574164D01*
X1620061Y572997D01*
X1620934Y570956D01*
X1621153Y568622D01*
X1620934Y566289D01*
X1620061Y564247D01*
X1618751Y563081D01*
X1617441Y562789D01*
G01X1638871D02*
Y574455D01*
G01Y572414D02*
X1637998Y573580D01*
X1636687Y574164D01*
X1635159Y574455D01*
X1633631Y573872D01*
X1632321Y572706D01*
X1631447Y570956D01*
X1631011Y568622D01*
X1631447Y566289D01*
X1632321Y564539D01*
X1633631Y563372D01*
X1635159Y562789D01*
X1636687Y563081D01*
X1637998Y563955D01*
X1638871Y565122D01*
G01X1649384Y562789D02*
Y574455D01*
G01Y572122D02*
X1650476Y573289D01*
X1651568Y574164D01*
X1653096Y574455D01*
X1654187Y574164D01*
X1655498Y573289D01*
G01X1673871Y580289D02*
Y562789D01*
G01Y565413D02*
X1672998Y563955D01*
X1671687Y563081D01*
X1670159Y562789D01*
X1668413Y563372D01*
X1667103Y564830D01*
X1666229Y566580D01*
X1666011Y568622D01*
X1666229Y570664D01*
X1667103Y572414D01*
X1668413Y573872D01*
X1670159Y574455D01*
X1671687Y574164D01*
X1672779Y573580D01*
X1673871Y572414D01*
G01X1704941Y562789D02*
X1703631Y563081D01*
X1702321Y564247D01*
X1701447Y566289D01*
X1701011Y568622D01*
X1701447Y570956D01*
X1702321Y572997D01*
X1703631Y574164D01*
X1704941Y574455D01*
X1706251Y574164D01*
X1707561Y572997D01*
X1708434Y570956D01*
X1708653Y568622D01*
X1708434Y566289D01*
X1707561Y564247D01*
X1706251Y563081D01*
X1704941Y562789D01*
G01X1718729Y574455D02*
Y566289D01*
X1719603Y564247D01*
X1720913Y563081D01*
X1722441Y562789D01*
X1723969Y563081D01*
X1725279Y564247D01*
X1726153Y566289D01*
G01Y562789D02*
Y574455D01*
G01X1739941Y580289D02*
Y562789D01*
G01X1736884Y574455D02*
X1742998D01*
G01X1757441Y562789D02*
Y580289D01*
G01X1774941Y574455D02*
Y562789D01*
G01Y579122D02*
X1774504Y579414D01*
Y579997D01*
X1774941Y580289D01*
X1775378Y579997D01*
Y579414D01*
X1774941Y579122D01*
G01X1788729Y562789D02*
Y574455D01*
G01Y571539D02*
X1789603Y572997D01*
X1790913Y574164D01*
X1792659Y574455D01*
X1794187Y574164D01*
X1795498Y572997D01*
X1796153Y570956D01*
Y562789D01*
G01X1806666Y570664D02*
X1813653D01*
X1812998Y572706D01*
X1811906Y573872D01*
X1810378Y574455D01*
X1808849Y574164D01*
X1807539Y573289D01*
X1806666Y571247D01*
X1806229Y569497D01*
Y567747D01*
X1806666Y565997D01*
X1807758Y564247D01*
X1809068Y563081D01*
X1810596Y562789D01*
X1812124Y563372D01*
X1813653Y565122D01*
G01X1827441Y562206D02*
X1827004Y562497D01*
Y563081D01*
X1827441Y563372D01*
X1827878Y563081D01*
Y562497D01*
X1827441Y562206D01*
G01X1402638Y631506D02*
X1412244Y644339D01*
G01X1407441Y646672D02*
Y629172D01*
G01X1412244Y631506D02*
X1402638Y644339D01*
G01X1400891Y637922D02*
X1413991D01*
G01X1439603D02*
X1445279D01*
G01X1472638Y632089D02*
Y649589D01*
X1477004D01*
X1478751Y648714D01*
X1480061Y647547D01*
X1481153Y645798D01*
X1482026Y643755D01*
X1482244Y640839D01*
X1482026Y637922D01*
X1481153Y635880D01*
X1480061Y634130D01*
X1478751Y632964D01*
X1477004Y632089D01*
X1472638D01*
G01X1491666Y639964D02*
X1498653D01*
X1497998Y642006D01*
X1496906Y643172D01*
X1495378Y643755D01*
X1493849Y643464D01*
X1492539Y642589D01*
X1491666Y640547D01*
X1491229Y638797D01*
Y637047D01*
X1491666Y635297D01*
X1492758Y633547D01*
X1494068Y632381D01*
X1495596Y632089D01*
X1497124Y632672D01*
X1498653Y634422D01*
G01X1508729Y632089D02*
Y643755D01*
G01Y640839D02*
X1509603Y642297D01*
X1510913Y643464D01*
X1512659Y643755D01*
X1514187Y643464D01*
X1515498Y642297D01*
X1516153Y640256D01*
Y632089D01*
G01X1529941D02*
X1528631Y632381D01*
X1527321Y633547D01*
X1526447Y635589D01*
X1526011Y637922D01*
X1526447Y640256D01*
X1527321Y642297D01*
X1528631Y643464D01*
X1529941Y643755D01*
X1531251Y643464D01*
X1532561Y642297D01*
X1533434Y640256D01*
X1533653Y637922D01*
X1533434Y635589D01*
X1532561Y633547D01*
X1531251Y632381D01*
X1529941Y632089D01*
G01X1547441Y649589D02*
Y632089D01*
G01X1544384Y643755D02*
X1550498D01*
G01X1561666Y639964D02*
X1568653D01*
X1567998Y642006D01*
X1566906Y643172D01*
X1565378Y643755D01*
X1563849Y643464D01*
X1562539Y642589D01*
X1561666Y640547D01*
X1561229Y638797D01*
Y637047D01*
X1561666Y635297D01*
X1562758Y633547D01*
X1564068Y632381D01*
X1565596Y632089D01*
X1567124Y632672D01*
X1568653Y634422D01*
G01X1579166Y634130D02*
X1580258Y632964D01*
X1581786Y632089D01*
X1583096D01*
X1584406Y632672D01*
X1585279Y633547D01*
X1585716Y634713D01*
X1585498Y636464D01*
X1584624Y637339D01*
X1580694Y639089D01*
X1579821Y641131D01*
X1580258Y642589D01*
X1581131Y643464D01*
X1582441Y643755D01*
X1583751Y643464D01*
X1585061Y642589D01*
G01X1617441Y649589D02*
Y632089D01*
G01X1614384Y643755D02*
X1620498D01*
G01X1631229Y632089D02*
Y649589D01*
G01Y641131D02*
X1632321Y642589D01*
X1633413Y643464D01*
X1635159Y643755D01*
X1636469Y643464D01*
X1637998Y642297D01*
X1638653Y640547D01*
Y632089D01*
G01X1656371D02*
Y643755D01*
G01Y641714D02*
X1655498Y642880D01*
X1654187Y643464D01*
X1652659Y643755D01*
X1651131Y643172D01*
X1649821Y642006D01*
X1648947Y640256D01*
X1648511Y637922D01*
X1648947Y635589D01*
X1649821Y633839D01*
X1651131Y632672D01*
X1652659Y632089D01*
X1654187Y632381D01*
X1655498Y633255D01*
X1656371Y634422D01*
G01X1669941Y649589D02*
Y632089D01*
G01X1666884Y643755D02*
X1672998D01*
G01X1698391Y649589D02*
X1701447Y632089D01*
X1704941Y649589D01*
X1708434Y632089D01*
X1711491Y649589D01*
G01X1719821D02*
X1725061D01*
G01X1722441D02*
Y632089D01*
G01X1719821D02*
X1725061D01*
G01X1735138D02*
Y649589D01*
X1739504D01*
X1741251Y648714D01*
X1742561Y647547D01*
X1743653Y645798D01*
X1744526Y643755D01*
X1744744Y640839D01*
X1744526Y637922D01*
X1743653Y635880D01*
X1742561Y634130D01*
X1741251Y632964D01*
X1739504Y632089D01*
X1735138D01*
G01X1757441Y649589D02*
Y632089D01*
G01X1752419Y649589D02*
X1762463D01*
G01X1770356Y632089D02*
Y649589D01*
G01X1779526D02*
Y632089D01*
G01Y640839D02*
X1770356D01*
G01X1477441Y609105D02*
Y597439D01*
G01Y613772D02*
X1477004Y614064D01*
Y614647D01*
X1477441Y614939D01*
X1477878Y614647D01*
Y614064D01*
X1477441Y613772D01*
G01X1491666Y599480D02*
X1492758Y598314D01*
X1494286Y597439D01*
X1495596D01*
X1496906Y598022D01*
X1497779Y598897D01*
X1498216Y600063D01*
X1497998Y601814D01*
X1497124Y602689D01*
X1493194Y604439D01*
X1492321Y606481D01*
X1492758Y607939D01*
X1493631Y608814D01*
X1494941Y609105D01*
X1496251Y608814D01*
X1497561Y607939D01*
G01X1524919Y597439D02*
Y614939D01*
X1534963Y597439D01*
Y614939D01*
G01X1547441Y597439D02*
X1545694Y597731D01*
X1544166Y598897D01*
X1542856Y600647D01*
X1541982Y602689D01*
X1541546Y605022D01*
Y607356D01*
X1541982Y609689D01*
X1542856Y611731D01*
X1544166Y613480D01*
X1545694Y614647D01*
X1547441Y614939D01*
X1549187Y614647D01*
X1550716Y613480D01*
X1552026Y611731D01*
X1552900Y609689D01*
X1553336Y607356D01*
Y605022D01*
X1552900Y602689D01*
X1552026Y600647D01*
X1550716Y598897D01*
X1549187Y597731D01*
X1547441Y597439D01*
G01X1564941Y614939D02*
Y597439D01*
G01X1559919Y614939D02*
X1569963D01*
G01X1596229Y609105D02*
Y600939D01*
X1597103Y598897D01*
X1598413Y597731D01*
X1599941Y597439D01*
X1601469Y597731D01*
X1602779Y598897D01*
X1603653Y600939D01*
G01Y597439D02*
Y609105D01*
G01X1614166Y599480D02*
X1615258Y598314D01*
X1616786Y597439D01*
X1618096D01*
X1619406Y598022D01*
X1620279Y598897D01*
X1620716Y600063D01*
X1620498Y601814D01*
X1619624Y602689D01*
X1615694Y604439D01*
X1614821Y606481D01*
X1615258Y607939D01*
X1616131Y608814D01*
X1617441Y609105D01*
X1618751Y608814D01*
X1620061Y607939D01*
G01X1631666Y605314D02*
X1638653D01*
X1637998Y607356D01*
X1636906Y608522D01*
X1635378Y609105D01*
X1633849Y608814D01*
X1632539Y607939D01*
X1631666Y605897D01*
X1631229Y604147D01*
Y602397D01*
X1631666Y600647D01*
X1632758Y598897D01*
X1634068Y597731D01*
X1635596Y597439D01*
X1637124Y598022D01*
X1638653Y599772D01*
G01X1656371Y614939D02*
Y597439D01*
G01Y600063D02*
X1655498Y598605D01*
X1654187Y597731D01*
X1652659Y597439D01*
X1650913Y598022D01*
X1649603Y599480D01*
X1648729Y601230D01*
X1648511Y603272D01*
X1648729Y605314D01*
X1649603Y607064D01*
X1650913Y608522D01*
X1652659Y609105D01*
X1654187Y608814D01*
X1655279Y608230D01*
X1656371Y607064D01*
G01X1687441Y609105D02*
Y597439D01*
G01Y613772D02*
X1687004Y614064D01*
Y614647D01*
X1687441Y614939D01*
X1687878Y614647D01*
Y614064D01*
X1687441Y613772D01*
G01X1701229Y597439D02*
Y609105D01*
G01Y606189D02*
X1702103Y607647D01*
X1703413Y608814D01*
X1705159Y609105D01*
X1706687Y608814D01*
X1707998Y607647D01*
X1708653Y605606D01*
Y597439D01*
G01X1739941Y614939D02*
Y597439D01*
G01X1736884Y609105D02*
X1742998D01*
G01X1753729Y597439D02*
Y614939D01*
G01Y606481D02*
X1754821Y607939D01*
X1755913Y608814D01*
X1757659Y609105D01*
X1758969Y608814D01*
X1760498Y607647D01*
X1761153Y605897D01*
Y597439D01*
G01X1774941Y609105D02*
Y597439D01*
G01Y613772D02*
X1774504Y614064D01*
Y614647D01*
X1774941Y614939D01*
X1775378Y614647D01*
Y614064D01*
X1774941Y613772D01*
G01X1789166Y599480D02*
X1790258Y598314D01*
X1791786Y597439D01*
X1793096D01*
X1794406Y598022D01*
X1795279Y598897D01*
X1795716Y600063D01*
X1795498Y601814D01*
X1794624Y602689D01*
X1790694Y604439D01*
X1789821Y606481D01*
X1790258Y607939D01*
X1791131Y608814D01*
X1792441Y609105D01*
X1793751Y608814D01*
X1795061Y607939D01*
G01X1827441Y597439D02*
Y614939D01*
G01X1848871Y597439D02*
Y609105D01*
G01Y607064D02*
X1847998Y608230D01*
X1846687Y608814D01*
X1845159Y609105D01*
X1843631Y608522D01*
X1842321Y607356D01*
X1841447Y605606D01*
X1841011Y603272D01*
X1841447Y600939D01*
X1842321Y599189D01*
X1843631Y598022D01*
X1845159Y597439D01*
X1846687Y597731D01*
X1847998Y598605D01*
X1848871Y599772D01*
G01X1857856Y592189D02*
X1859166Y591606D01*
X1860913Y592189D01*
X1862004Y593355D01*
X1862878Y594814D01*
X1864187Y599480D01*
X1867026Y609105D01*
G01X1860039D02*
X1864187Y599480D01*
G01X1876666Y605314D02*
X1883653D01*
X1882998Y607356D01*
X1881906Y608522D01*
X1880378Y609105D01*
X1878849Y608814D01*
X1877539Y607939D01*
X1876666Y605897D01*
X1876229Y604147D01*
Y602397D01*
X1876666Y600647D01*
X1877758Y598897D01*
X1879068Y597731D01*
X1880596Y597439D01*
X1882124Y598022D01*
X1883653Y599772D01*
G01X1894384Y597439D02*
Y609105D01*
G01Y606772D02*
X1895476Y607939D01*
X1896568Y608814D01*
X1898096Y609105D01*
X1899187Y608814D01*
X1900498Y607939D01*
G01X-20271Y15000D02*
Y676339D01*
G01Y15000D02*
G03X-5271Y0I15000J0D01*
G01Y691339D02*
G03X-20271Y676339I0J-15000D01*
G01X0Y37795D02*
G03X3937Y33858I3937J0D01*
G01X21063Y29921D02*
G03X17126Y33858I-3937J0D01*
G01X3937D02*
X17126D01*
G01X299409Y0D02*
X23031D01*
G01X21063Y1969D02*
X23031Y0D01*
G01X21063Y1969D02*
Y29921D01*
G01X0Y102756D02*
Y37795D01*
G01D02*
G03X-7874I-3937J0D01*
G01X3937Y25984D02*
X13189D01*
G01X-7874Y37795D02*
G03X3937Y25984I11811J0D01*
G01X13189Y0D02*
X-5271D01*
G01X13189Y25984D02*
Y0D01*
G01X3937Y106693D02*
G03X0Y102756I0J-3937D01*
G01X-7874Y68504D02*
G03X0I3937J0D01*
G01X-7874D02*
Y122737D01*
G01X0Y118504D02*
G03X3937Y114567I3937J0D01*
G01Y157382D02*
G03X0Y153445I0J-3937D01*
G01X17126Y157382D02*
G03X21063Y161319I0J3937D01*
G01X0Y118504D02*
Y153445D01*
G01X21063Y219292D02*
Y161319D01*
G01D02*
Y187402D01*
G01X143701Y114567D02*
X3937D01*
G01Y157382D02*
X17126D01*
G01X3937Y106693D02*
X143701D01*
G01X-7874Y153445D02*
Y157382D01*
G01Y153445D02*
G03X0I3937J0D01*
G01Y122737D02*
G03X-7874I-3937J0D01*
G01X-10433Y161070D02*
G03X-7874Y157382I3937J0D01*
G01X-10433Y265210D02*
Y161070D01*
G01X51378Y181496D02*
G03X47441Y177559I0J-3937D01*
G01Y165748D02*
G03X51378Y161811I3937J0D01*
G01X47441Y165748D02*
Y177559D01*
G01X23031Y221260D02*
X21063Y219292D01*
G01X23031Y221260D02*
X63189D01*
G01X0Y272835D02*
G03X3937Y268898I3937J0D01*
G01X21063Y264961D02*
G03X17126Y268898I-3937J0D01*
G01X3937D02*
X17126D01*
G01X299409Y235040D02*
X23031D01*
G01X21063Y237008D02*
X23031Y235040D01*
G01X21063Y237008D02*
Y264961D01*
G01X0Y337796D02*
Y272835D01*
G01D02*
G03X-7874I-3937J0D01*
G01Y268898D02*
G03X-10433Y265210I1378J-3688D01*
G01X-7874Y268898D02*
Y272835D01*
G01X3937Y341733D02*
G03X0Y337796I0J-3937D01*
G01X3937Y341733D02*
X143701D01*
G01X-7874Y303543D02*
Y357781D01*
G01Y303544D02*
G03X0I3937J0D01*
G01X47441Y400788D02*
G03X51378Y396851I3937J0D01*
G01X47441Y400788D02*
Y412599D01*
G01X0Y353544D02*
G03X3937Y349607I3937J0D01*
G01Y392422D02*
G03X0Y388485I0J-3937D01*
G01X17126Y392422D02*
G03X21063Y396359I0J3937D01*
G01X0Y353544D02*
Y388485D01*
G01X21063Y454331D02*
Y396359D01*
G01D02*
Y422441D01*
G01X143701Y349607D02*
X3937D01*
G01Y392422D02*
X17126D01*
G01X-7874Y388480D02*
Y392422D01*
G01Y388485D02*
G03X0I3937J0D01*
G01Y357776D02*
G03X-7874I-3937J0D01*
G01X-10433Y396110D02*
G03X-7874Y392422I3937J0D01*
G01X-10433Y500250D02*
Y396110D01*
G01X51378Y416536D02*
G03X47441Y412599I0J-3937D01*
G01X23031Y456300D02*
X21063Y454331D01*
G01X23031Y456300D02*
X63189D01*
G01X0Y507874D02*
G03X3937Y503937I3937J0D01*
G01X21063Y500000D02*
G03X17126Y503937I-3937J0D01*
G01X3937D02*
X17126D01*
G01X299409Y470079D02*
X23031D01*
G01X21063Y472048D02*
X23031Y470079D01*
G01X21063Y472048D02*
Y500000D01*
G01X0Y572835D02*
Y507874D01*
G01D02*
G03X-7874I-3937J0D01*
G01Y503937D02*
Y507880D01*
G01Y503937D02*
G03X-10433Y500250I1378J-3688D01*
G01X3937Y576772D02*
G03X0Y572835I0J-3937D01*
G01X3937Y576772D02*
X143701D01*
G01X0Y588583D02*
G03X3937Y584646I3937J0D01*
G01X0Y588583D02*
Y623524D01*
G01X143701Y584646D02*
X3937D01*
G01X-7874Y538578D02*
Y592823D01*
G01Y538583D02*
G03X0I3937J0D01*
G01X51378Y651576D02*
G03X47441Y647639I0J-3937D01*
G01Y635828D02*
G03X51378Y631891I3937J0D01*
G01X47441Y635828D02*
Y647639D01*
G01X3937Y627461D02*
G03X0Y623524I0J-3937D01*
G01X17126Y627461D02*
G03X21063Y631398I0J3937D01*
G01Y689371D02*
Y631398D01*
G01D02*
Y657481D01*
G01X3937Y627461D02*
X17126D01*
G01X1830Y651994D02*
G03I-4292J0D01*
G01X-7874Y623517D02*
Y623536D01*
G01X13189Y691339D02*
Y635335D01*
G01X3937D02*
X13189D01*
G01X3937D02*
G03X-7874Y623524I0J-11811D01*
G01D02*
G03X0I3937J0D01*
G01Y592816D02*
G03X-7874I-3937J0D01*
G01X23031Y691339D02*
X21063Y689371D01*
G01X23031Y691339D02*
X63189D01*
G01X13189D02*
X-5271D01*
G01X63189Y161811D02*
G03X67126Y165748I0J3937D01*
G01X73425D02*
G03X77362Y161811I3937J0D01*
G01X89173D02*
G03X93110Y165748I0J3937D01*
G01X99409D02*
G03X103346Y161811I3937J0D01*
G01X63189D02*
X51378D01*
G01X89173D02*
X77362D01*
G01X115157D02*
X103346D01*
G01X89173Y114567D02*
G03Y106693I0J-3937D01*
G01X58465D02*
G03Y114567I0J3937D01*
G01X67126Y177559D02*
G03X63189Y181496I-3937J0D01*
G01X77362D02*
G03X73425Y177559I0J-3937D01*
G01X93110D02*
G03X89173Y181496I-3937J0D01*
G01X103346D02*
G03X99409Y177559I0J-3937D01*
G01X67126D02*
Y165748D01*
G01X73425D02*
Y177559D01*
G01X93110D02*
Y165748D01*
G01X99409D02*
Y177559D01*
G01X103346Y181496D02*
X115157D01*
G01X77362D02*
X89173D01*
G01X51378D02*
X63189D01*
G01X65157Y191930D02*
G03X72638I3740J0D01*
G01X65157Y219292D02*
Y191930D01*
G01X74606Y221260D02*
X72638Y219292D01*
G01D02*
Y191930D01*
G01X65157Y219292D02*
X63189Y221260D01*
G01X74606D02*
X350984D01*
G01X89173Y349607D02*
G03Y341733I0J-3937D01*
G01X58465D02*
G03Y349607I0J3937D01*
G01X63189Y396851D02*
G03X67126Y400788I0J3937D01*
G01X73425D02*
G03X77362Y396851I3937J0D01*
G01X89173D02*
G03X93110Y400788I0J3937D01*
G01X99409D02*
G03X103346Y396851I3937J0D01*
G01X67126Y412599D02*
Y400788D01*
G01X73425D02*
Y412599D01*
G01X93110D02*
Y400788D01*
G01X99409D02*
Y412599D01*
G01X63189Y396851D02*
X51378D01*
G01X89173D02*
X77362D01*
G01X115157D02*
X103346D01*
G01X67126Y412599D02*
G03X63189Y416536I-3937J0D01*
G01X77362D02*
G03X73425Y412599I0J-3937D01*
G01X93110D02*
G03X89173Y416536I-3937J0D01*
G01X103346D02*
G03X99409Y412599I0J-3937D01*
G01X103346Y416536D02*
X115157D01*
G01X77362D02*
X89173D01*
G01X51378D02*
X63189D01*
G01X65157Y426969D02*
G03X72638I3740J0D01*
G01X65157Y454331D02*
Y426969D01*
G01X74606Y456300D02*
X72638Y454331D01*
G01D02*
Y426969D01*
G01X65157Y454331D02*
X63189Y456300D01*
G01X74606D02*
X350984D01*
G01X89173Y584646D02*
G03Y576772I0J-3937D01*
G01X58465D02*
G03Y584646I0J3937D01*
G01X67126Y647639D02*
G03X63189Y651576I-3937J0D01*
G01Y631891D02*
G03X67126Y635828I0J3937D01*
G01X73425D02*
G03X77362Y631891I3937J0D01*
G01Y651576D02*
G03X73425Y647639I0J-3937D01*
G01X93110D02*
G03X89173Y651576I-3937J0D01*
G01Y631891D02*
G03X93110Y635828I0J3937D01*
G01X103346Y651576D02*
G03X99409Y647639I0J-3937D01*
G01Y635828D02*
G03X103346Y631891I3937J0D01*
G01X67126Y647639D02*
Y635828D01*
G01X73425D02*
Y647639D01*
G01X93110D02*
Y635828D01*
G01X99409D02*
Y647639D01*
G01X63189Y631891D02*
X51378D01*
G01X89173D02*
X77362D01*
G01X115157D02*
X103346D01*
G01Y651576D02*
X115157D01*
G01X77362D02*
X89173D01*
G01X51378D02*
X63189D01*
G01X65157Y662009D02*
G03X72638I3740J0D01*
G01X65157Y689371D02*
Y662009D01*
G01X74606Y691339D02*
X72638Y689371D01*
G01D02*
Y662009D01*
G01X65157Y689371D02*
X63189Y691339D01*
G01X74606D02*
X350984D01*
G01X147638Y102756D02*
G03X151575Y98819I3937J0D01*
G01X147638Y102756D02*
G03X143701Y106693I-3937J0D01*
G01X147638Y102756D02*
G03X151575Y98819I3937J0D01*
G01X147638Y102756D02*
G03X143701Y106693I-3937J0D01*
G01X147638Y102756D02*
G03X151575Y98819I3937J0D01*
G01X147638Y102756D02*
G03X143701Y106693I-3937J0D01*
G01X151575Y98819D02*
X222441D01*
G01X115157Y161811D02*
G03X119094Y165748I0J3937D01*
G01X151575Y122441D02*
G03X147638Y118504I0J-3937D01*
G01X143701Y114567D02*
G03X147638Y118504I0J3937D01*
G01X143701Y114567D02*
X112205D01*
G01X143701D02*
G03X147638Y118504I0J3937D01*
G01X151575Y122441D02*
G03X147638Y118504I0J-3937D01*
G01X151575Y122441D02*
G03X147638Y118504I0J-3937D01*
G01X143701Y114567D02*
G03X147638Y118504I0J3937D01*
G01X222441Y122441D02*
X151575D01*
G01X143701Y106693D02*
X112205D01*
G01X119094Y177559D02*
G03X115157Y181496I-3937J0D01*
G01X119094Y177559D02*
Y165748D01*
G01X147638Y337796D02*
G03X151575Y333859I3937J0D01*
G01X147638Y337796D02*
G03X143701Y341733I-3937J0D01*
G01D02*
X112205D01*
G01X147638Y337796D02*
G03X151575Y333859I3937J0D01*
G01X147638Y337796D02*
G03X143701Y341733I-3937J0D01*
G01X147638Y337796D02*
G03X151575Y333859I3937J0D01*
G01X147638Y337796D02*
G03X143701Y341733I-3937J0D01*
G01X151575Y333859D02*
X222441D01*
G01X115157Y396851D02*
G03X119094Y400788I0J3937D01*
G01Y412599D02*
Y400788D01*
G01X151575Y357481D02*
G03X147638Y353544I0J-3937D01*
G01X143701Y349607D02*
G03X147638Y353544I0J3937D01*
G01X143701Y349607D02*
X112205D01*
G01X143701D02*
G03X147638Y353544I0J3937D01*
G01X151575Y357481D02*
G03X147638Y353544I0J-3937D01*
G01X151575Y357481D02*
G03X147638Y353544I0J-3937D01*
G01X143701Y349607D02*
G03X147638Y353544I0J3937D01*
G01X222441Y357481D02*
X151575D01*
G01X119094Y412599D02*
G03X115157Y416536I-3937J0D01*
G01X147638Y572835D02*
G03X151575Y568898I3937J0D01*
G01X147638Y572835D02*
G03X143701Y576772I-3937J0D01*
G01D02*
X112205D01*
G01X147638Y572835D02*
G03X151575Y568898I3937J0D01*
G01X147638Y572835D02*
G03X143701Y576772I-3937J0D01*
G01X147638Y572835D02*
G03X151575Y568898I3937J0D01*
G01X147638Y572835D02*
G03X143701Y576772I-3937J0D01*
G01X151575Y568898D02*
X222441D01*
G01X151575Y592520D02*
G03X147638Y588583I0J-3937D01*
G01X143701Y584646D02*
G03X147638Y588583I0J3937D01*
G01X143701Y584646D02*
X112205D01*
G01X143701D02*
G03X147638Y588583I0J3937D01*
G01X151575Y592520D02*
G03X147638Y588583I0J-3937D01*
G01X151575Y592520D02*
G03X147638Y588583I0J-3937D01*
G01X143701Y584646D02*
G03X147638Y588583I0J3937D01*
G01X119094Y647639D02*
G03X115157Y651576I-3937J0D01*
G01Y631891D02*
G03X119094Y635828I0J3937D01*
G01Y647639D02*
Y635828D01*
G01X222441Y592520D02*
X151575D01*
G01X222441Y98819D02*
G03X226378Y102756I0J3937D01*
G01X230315Y106693D02*
G03X226378Y102756I0J-3937D01*
G01X230315Y106693D02*
G03X226378Y102756I0J-3937D01*
G01X222441Y98819D02*
G03X226378Y102756I0J3937D01*
G01X222441Y98819D02*
G03X226378Y102756I0J3937D01*
G01X230315Y106693D02*
G03X226378Y102756I0J-3937D01*
G01Y118504D02*
G03X222441Y122441I-3937J0D01*
G01X226378Y118504D02*
G03X230315Y114567I3937J0D01*
G01D02*
X261811D01*
G01X226378Y118504D02*
G03X222441Y122441I-3937J0D01*
G01X226378Y118504D02*
G03X230315Y114567I3937J0D01*
G01X226378Y118504D02*
G03X222441Y122441I-3937J0D01*
G01X226378Y118504D02*
G03X230315Y114567I3937J0D01*
G01X370079D02*
X230315D01*
G01Y106693D02*
X261811D01*
G01X230315D02*
X370079D01*
G01X222441Y333859D02*
G03X226378Y337796I0J3937D01*
G01X230315Y341733D02*
G03X226378Y337796I0J-3937D01*
G01X230315Y341733D02*
X261811D01*
G01X230315D02*
G03X226378Y337796I0J-3937D01*
G01X222441Y333859D02*
G03X226378Y337796I0J3937D01*
G01X222441Y333859D02*
G03X226378Y337796I0J3937D01*
G01X230315Y341733D02*
G03X226378Y337796I0J-3937D01*
G01X230315Y341733D02*
X370079D01*
G01X226378Y353544D02*
G03X222441Y357481I-3937J0D01*
G01X226378Y353544D02*
G03X230315Y349607I3937J0D01*
G01D02*
X261811D01*
G01X226378Y353544D02*
G03X222441Y357481I-3937J0D01*
G01X226378Y353544D02*
G03X230315Y349607I3937J0D01*
G01X226378Y353544D02*
G03X222441Y357481I-3937J0D01*
G01X226378Y353544D02*
G03X230315Y349607I3937J0D01*
G01X370079D02*
X230315D01*
G01X222441Y568898D02*
G03X226378Y572835I0J3937D01*
G01X230315Y576772D02*
G03X226378Y572835I0J-3937D01*
G01X230315Y576772D02*
X261811D01*
G01X230315D02*
G03X226378Y572835I0J-3937D01*
G01X222441Y568898D02*
G03X226378Y572835I0J3937D01*
G01X222441Y568898D02*
G03X226378Y572835I0J3937D01*
G01X230315Y576772D02*
G03X226378Y572835I0J-3937D01*
G01X230315Y576772D02*
X370079D01*
G01X226378Y588583D02*
G03X222441Y592520I-3937J0D01*
G01X226378Y588583D02*
G03X230315Y584646I3937J0D01*
G01D02*
X261811D01*
G01X226378Y588583D02*
G03X222441Y592520I-3937J0D01*
G01X226378Y588583D02*
G03X230315Y584646I3937J0D01*
G01X226378Y588583D02*
G03X222441Y592520I-3937J0D01*
G01X226378Y588583D02*
G03X230315Y584646I3937J0D01*
G01X370079D02*
X230315D01*
G01X280906Y43701D02*
G03X284843Y39764I3937J0D01*
G01X270669D02*
G03X274606Y43701I0J3937D01*
G01X254921D02*
G03X258858Y39764I3937J0D01*
G01X270669D02*
X258858D01*
G01X296654D02*
X284843D01*
G01Y59449D02*
G03X280906Y55512I0J-3937D01*
G01X258858Y59449D02*
G03X254921Y55512I0J-3937D01*
G01X274606D02*
G03X270669Y59449I-3937J0D01*
G01X280906Y43701D02*
Y55512D01*
G01X274606D02*
Y43701D01*
G01X254921D02*
Y55512D01*
G01X284843Y59449D02*
X296654D01*
G01X258858D02*
X270669D01*
G01X284843Y106693D02*
G03Y114567I0J3937D01*
G01X280906Y278741D02*
G03X284843Y274804I3937J0D01*
G01X270669D02*
G03X274606Y278741I0J3937D01*
G01X254921D02*
G03X258858Y274804I3937J0D01*
G01X280906Y278741D02*
Y290552D01*
G01X274606D02*
Y278741D01*
G01X254921D02*
Y290552D01*
G01X270669Y274804D02*
X258858D01*
G01X296654D02*
X284843D01*
G01Y294489D02*
G03X280906Y290552I0J-3937D01*
G01X258858Y294489D02*
G03X254921Y290552I0J-3937D01*
G01X274606D02*
G03X270669Y294489I-3937J0D01*
G01X284843D02*
X296654D01*
G01X258858D02*
X270669D01*
G01X284843Y341733D02*
G03Y349607I0J3937D01*
G01X280906Y513780D02*
G03X284843Y509843I3937J0D01*
G01Y529528D02*
G03X280906Y525591I0J-3937D01*
G01X270669Y509843D02*
G03X274606Y513780I0J3937D01*
G01X254921D02*
G03X258858Y509843I3937J0D01*
G01Y529528D02*
G03X254921Y525591I0J-3937D01*
G01X274606D02*
G03X270669Y529528I-3937J0D01*
G01X280906Y513780D02*
Y525591D01*
G01X274606D02*
Y513780D01*
G01X254921D02*
Y525591D01*
G01X284843Y529528D02*
X296654D01*
G01X258858D02*
X270669D01*
G01Y509843D02*
X258858D01*
G01X296654D02*
X284843D01*
G01Y576772D02*
G03Y584646I0J3937D01*
G01X322638Y39764D02*
G03X326575Y43701I0J3937D01*
G01X306890D02*
G03X310827Y39764I3937J0D01*
G01X296654D02*
G03X300591Y43701I0J3937D01*
G01X322638Y39764D02*
X310827D01*
G01X308858Y29331D02*
G03X301378I-3740J0D01*
G01X350984Y0D02*
X352953Y1969D01*
G01X308858D02*
Y29331D01*
G01X299409Y0D02*
X301378Y1969D01*
G01D02*
Y29331D01*
G01X308858Y1969D02*
X310827Y0D01*
G01X350984D02*
X310827D01*
G01Y59449D02*
G03X306890Y55512I0J-3937D01*
G01X326575D02*
G03X322638Y59449I-3937J0D01*
G01X300591Y55512D02*
G03X296654Y59449I-3937J0D01*
G01X326575Y55512D02*
Y43701D01*
G01X306890D02*
Y55512D01*
G01X300591D02*
Y43701D01*
G01X310827Y59449D02*
X322638D01*
G01X315551Y114567D02*
G03Y106693I0J-3937D01*
G01X352953Y219292D02*
X350984Y221260D01*
G01X322638Y274804D02*
G03X326575Y278741I0J3937D01*
G01X306890D02*
G03X310827Y274804I3937J0D01*
G01X296654D02*
G03X300591Y278741I0J3937D01*
G01X326575Y290552D02*
Y278741D01*
G01X306890D02*
Y290552D01*
G01X300591D02*
Y278741D01*
G01X322638Y274804D02*
X310827D01*
G01X308858Y264370D02*
G03X301378I-3740J0D01*
G01X350984Y235040D02*
X352953Y237008D01*
G01X308858D02*
Y264370D01*
G01X299409Y235040D02*
X301378Y237008D01*
G01D02*
Y264370D01*
G01X308858Y237008D02*
X310827Y235040D01*
G01X350984D02*
X310827D01*
G01Y294489D02*
G03X306890Y290552I0J-3937D01*
G01X326575D02*
G03X322638Y294489I-3937J0D01*
G01X300591Y290552D02*
G03X296654Y294489I-3937J0D01*
G01X310827D02*
X322638D01*
G01X315551Y349607D02*
G03Y341733I0J-3937D01*
G01X352953Y454331D02*
X350984Y456300D01*
G01X322638Y509843D02*
G03X326575Y513780I0J3937D01*
G01X306890D02*
G03X310827Y509843I3937J0D01*
G01Y529528D02*
G03X306890Y525591I0J-3937D01*
G01X326575D02*
G03X322638Y529528I-3937J0D01*
G01X300591Y525591D02*
G03X296654Y529528I-3937J0D01*
G01Y509843D02*
G03X300591Y513780I0J3937D01*
G01X326575Y525591D02*
Y513780D01*
G01X306890D02*
Y525591D01*
G01X300591D02*
Y513780D01*
G01X310827Y529528D02*
X322638D01*
G01Y509843D02*
X310827D01*
G01X308858Y499410D02*
G03X301378I-3740J0D01*
G01X350984Y470079D02*
X352953Y472048D01*
G01X308858D02*
Y499410D01*
G01X299409Y470079D02*
X301378Y472048D01*
G01D02*
Y499410D01*
G01X308858Y472048D02*
X310827Y470079D01*
G01X350984D02*
X310827D01*
G01X315551Y584646D02*
G03Y576772I0J-3937D01*
G01X352953Y689371D02*
X350984Y691339D01*
G01X381890Y37795D02*
G03X385827Y33858I3937J0D01*
G01X402953Y29921D02*
G03X399016Y33858I-3937J0D01*
G01X385827D02*
X399016D01*
G01X681299Y0D02*
X404921D01*
G01X402953Y1969D02*
X404921Y0D01*
G01X402953Y1969D02*
Y29921D01*
G01X381890Y102756D02*
Y37795D01*
G01X352953Y1969D02*
Y59941D01*
G01D02*
Y33858D01*
G01X385827Y106693D02*
G03X381890Y102756I0J-3937D01*
G01X374016D02*
G03X370079Y106693I-3937J0D01*
G01Y63878D02*
G03X374016Y67815I0J3937D01*
G01X356890Y63878D02*
G03X352953Y59941I0J-3937D01*
G01X374016Y102756D02*
Y67815D01*
G01X370079Y63878D02*
X356890D01*
G01X374016Y98524D02*
G03X381890I3937J0D01*
G01Y67815D02*
G03X374016I-3937J0D01*
G01X385827Y106693D02*
X525591D01*
G01X370079Y114567D02*
G03X374016Y118504I0J3937D01*
G01D02*
Y183465D01*
G01X381890Y118504D02*
G03X385827Y114567I3937J0D01*
G01Y157382D02*
G03X381890Y153445I0J-3937D01*
G01X399016Y157382D02*
G03X402953Y161319I0J3937D01*
G01X381890Y118504D02*
Y153445D01*
G01X402953Y219292D02*
Y161319D01*
G01D02*
Y187402D01*
G01X525591Y114567D02*
X385827D01*
G01Y157382D02*
X399016D01*
G01X374016Y153445D02*
G03X381890I3937J0D01*
G01Y122737D02*
G03X374016I-3937J0D01*
G01Y183465D02*
G03X370079Y187402I-3937J0D01*
G01X352953Y191339D02*
G03X356890Y187402I3937J0D01*
G01X370079D02*
X356890D01*
G01X352953Y219292D02*
Y191339D01*
G01X404921Y221260D02*
X402953Y219292D01*
G01X404921Y221260D02*
X445079D01*
G01X352953Y237008D02*
Y294981D01*
G01D02*
Y268898D01*
G01X381890Y272835D02*
G03X385827Y268898I3937J0D01*
G01X402953Y264961D02*
G03X399016Y268898I-3937J0D01*
G01X385827D02*
X399016D01*
G01X681299Y235040D02*
X404921D01*
G01X402953Y237008D02*
X404921Y235040D01*
G01X402953Y237008D02*
Y264961D01*
G01X381890Y337796D02*
Y272835D01*
G01X374016Y337796D02*
G03X370079Y341733I-3937J0D01*
G01Y298918D02*
G03X374016Y302855I0J3937D01*
G01X356890Y298918D02*
G03X352953Y294981I0J-3937D01*
G01X374016Y337796D02*
Y302855D01*
G01X370079Y298918D02*
X356890D01*
G01X385827Y341733D02*
G03X381890Y337796I0J-3937D01*
G01X385827Y341733D02*
X525591D01*
G01X374016Y333563D02*
G03X381890I3937J0D01*
G01Y302855D02*
G03X374016I-3937J0D01*
G01X381890Y353544D02*
G03X385827Y349607I3937J0D01*
G01Y392422D02*
G03X381890Y388485I0J-3937D01*
G01X399016Y392422D02*
G03X402953Y396359I0J3937D01*
G01X381890Y353544D02*
Y388485D01*
G01X402953Y454331D02*
Y396359D01*
G01D02*
Y422441D01*
G01X525591Y349607D02*
X385827D01*
G01Y392422D02*
X399016D01*
G01X370079Y349607D02*
G03X374016Y353544I0J3937D01*
G01D02*
Y418504D01*
G01Y388485D02*
G03X381890I3937J0D01*
G01Y357776D02*
G03X374016I-3937J0D01*
G01X404921Y456300D02*
X402953Y454331D01*
G01X404921Y456300D02*
X445079D01*
G01X374016Y418504D02*
G03X370079Y422441I-3937J0D01*
G01X352953Y426378D02*
G03X356890Y422441I3937J0D01*
G01X370079D02*
X356890D01*
G01X352953Y454331D02*
Y426378D01*
G01Y472048D02*
Y530020D01*
G01D02*
Y503937D01*
G01X381890Y507874D02*
G03X385827Y503937I3937J0D01*
G01X402953Y500000D02*
G03X399016Y503937I-3937J0D01*
G01X385827D02*
X399016D01*
G01X681299Y470079D02*
X404921D01*
G01X402953Y472048D02*
X404921Y470079D01*
G01X402953Y472048D02*
Y500000D01*
G01X381890Y572835D02*
Y507874D01*
G01X374016Y572835D02*
G03X370079Y576772I-3937J0D01*
G01Y533957D02*
G03X374016Y537894I0J3937D01*
G01X356890Y533957D02*
G03X352953Y530020I0J-3937D01*
G01X374016Y572835D02*
Y537894D01*
G01X370079Y533957D02*
X356890D01*
G01X385827Y576772D02*
G03X381890Y572835I0J-3937D01*
G01X385827Y576772D02*
X525591D01*
G01X381890Y588583D02*
G03X385827Y584646I3937J0D01*
G01X381890Y588583D02*
Y623524D01*
G01X525591Y584646D02*
X385827D01*
G01X370079D02*
G03X374016Y588583I0J3937D01*
G01D02*
Y653544D01*
G01Y568603D02*
G03X381890I3937J0D01*
G01Y537894D02*
G03X374016I-3937J0D01*
G01X385827Y627461D02*
G03X381890Y623524I0J-3937D01*
G01X399016Y627461D02*
G03X402953Y631398I0J3937D01*
G01Y689371D02*
Y631398D01*
G01D02*
Y657481D01*
G01X385827Y627461D02*
X399016D01*
G01X374016Y623524D02*
G03X381890I3937J0D01*
G01Y592816D02*
G03X374016I-3937J0D01*
G01X404921Y691339D02*
X402953Y689371D01*
G01X404921Y691339D02*
X445079D01*
G01X374016Y653544D02*
G03X370079Y657481I-3937J0D01*
G01X352953Y661418D02*
G03X356890Y657481I3937J0D01*
G01X370079D02*
X356890D01*
G01X352953Y689371D02*
Y661418D01*
G01X445079Y161811D02*
G03X449016Y165748I0J3937D01*
G01X429331D02*
G03X433268Y161811I3937J0D01*
G01X455315Y165748D02*
G03X459252Y161811I3937J0D01*
G01X471063D02*
G03X475000Y165748I0J3937D01*
G01X445079Y161811D02*
X433268D01*
G01X471063D02*
X459252D01*
G01X471063Y114567D02*
G03Y106693I0J-3937D01*
G01X440354D02*
G03Y114567I0J3937D01*
G01X433268Y181496D02*
G03X429331Y177559I0J-3937D01*
G01X449016D02*
G03X445079Y181496I-3937J0D01*
G01X459252D02*
G03X455315Y177559I0J-3937D01*
G01X475000D02*
G03X471063Y181496I-3937J0D01*
G01X429331Y165748D02*
Y177559D01*
G01X449016D02*
Y165748D01*
G01X455315D02*
Y177559D01*
G01X459252Y181496D02*
X471063D01*
G01X433268D02*
X445079D01*
G01X447047Y191930D02*
G03X454528I3740J0D01*
G01X447047Y219292D02*
Y191930D01*
G01X456496Y221260D02*
X454528Y219292D01*
G01D02*
Y191930D01*
G01X447047Y219292D02*
X445079Y221260D01*
G01X456496D02*
X732874D01*
G01X471063Y349607D02*
G03Y341733I0J-3937D01*
G01X440354D02*
G03Y349607I0J3937D01*
G01X445079Y396851D02*
G03X449016Y400788I0J3937D01*
G01X429331D02*
G03X433268Y396851I3937J0D01*
G01X455315Y400788D02*
G03X459252Y396851I3937J0D01*
G01X471063D02*
G03X475000Y400788I0J3937D01*
G01X429331D02*
Y412599D01*
G01X449016D02*
Y400788D01*
G01X455315D02*
Y412599D01*
G01X445079Y396851D02*
X433268D01*
G01X471063D02*
X459252D01*
G01X433268Y416536D02*
G03X429331Y412599I0J-3937D01*
G01X449016D02*
G03X445079Y416536I-3937J0D01*
G01X459252D02*
G03X455315Y412599I0J-3937D01*
G01X475000D02*
G03X471063Y416536I-3937J0D01*
G01X459252D02*
X471063D01*
G01X433268D02*
X445079D01*
G01X447047Y426969D02*
G03X454528I3740J0D01*
G01X447047Y454331D02*
Y426969D01*
G01X456496Y456300D02*
X454528Y454331D01*
G01D02*
Y426969D01*
G01X447047Y454331D02*
X445079Y456300D01*
G01X456496D02*
X732874D01*
G01X471063Y584646D02*
G03Y576772I0J-3937D01*
G01X440354D02*
G03Y584646I0J3937D01*
G01X433268Y651576D02*
G03X429331Y647639I0J-3937D01*
G01X449016D02*
G03X445079Y651576I-3937J0D01*
G01Y631891D02*
G03X449016Y635828I0J3937D01*
G01X429331D02*
G03X433268Y631891I3937J0D01*
G01X455315Y635828D02*
G03X459252Y631891I3937J0D01*
G01Y651576D02*
G03X455315Y647639I0J-3937D01*
G01X475000D02*
G03X471063Y651576I-3937J0D01*
G01Y631891D02*
G03X475000Y635828I0J3937D01*
G01X429331D02*
Y647639D01*
G01X449016D02*
Y635828D01*
G01X455315D02*
Y647639D01*
G01X445079Y631891D02*
X433268D01*
G01X471063D02*
X459252D01*
G01Y651576D02*
X471063D01*
G01X433268D02*
X445079D01*
G01X447047Y662009D02*
G03X454528I3740J0D01*
G01X447047Y689371D02*
Y662009D01*
G01X456496Y691339D02*
X454528Y689371D01*
G01D02*
Y662009D01*
G01X447047Y689371D02*
X445079Y691339D01*
G01X456496D02*
X732874D01*
G01X529528Y102756D02*
G03X533465Y98819I3937J0D01*
G01X529528Y102756D02*
G03X525591Y106693I-3937J0D01*
G01X529528Y102756D02*
G03X533465Y98819I3937J0D01*
G01X529528Y102756D02*
G03X525591Y106693I-3937J0D01*
G01X529528Y102756D02*
G03X533465Y98819I3937J0D01*
G01X529528Y102756D02*
G03X525591Y106693I-3937J0D01*
G01X533465Y98819D02*
X604331D01*
G01X525591Y106693D02*
X494094D01*
G01X497047Y161811D02*
G03X500984Y165748I0J3937D01*
G01X481299D02*
G03X485236Y161811I3937J0D01*
G01X497047D02*
X485236D01*
G01X533465Y122441D02*
G03X529528Y118504I0J-3937D01*
G01X525591Y114567D02*
G03X529528Y118504I0J3937D01*
G01X525591Y114567D02*
X494094D01*
G01X525591D02*
G03X529528Y118504I0J3937D01*
G01X533465Y122441D02*
G03X529528Y118504I0J-3937D01*
G01X533465Y122441D02*
G03X529528Y118504I0J-3937D01*
G01X525591Y114567D02*
G03X529528Y118504I0J3937D01*
G01X604331Y122441D02*
X533465D01*
G01X485236Y181496D02*
G03X481299Y177559I0J-3937D01*
G01X500984D02*
G03X497047Y181496I-3937J0D01*
G01X475000Y177559D02*
Y165748D01*
G01X481299D02*
Y177559D01*
G01X500984D02*
Y165748D01*
G01X485236Y181496D02*
X497047D01*
G01X529528Y337796D02*
G03X533465Y333859I3937J0D01*
G01X529528Y337796D02*
G03X525591Y341733I-3937J0D01*
G01D02*
X494094D01*
G01X529528Y337796D02*
G03X533465Y333859I3937J0D01*
G01X529528Y337796D02*
G03X525591Y341733I-3937J0D01*
G01X529528Y337796D02*
G03X533465Y333859I3937J0D01*
G01X529528Y337796D02*
G03X525591Y341733I-3937J0D01*
G01X533465Y333859D02*
X604331D01*
G01X497047Y396851D02*
G03X500984Y400788I0J3937D01*
G01X481299D02*
G03X485236Y396851I3937J0D01*
G01X475000Y412599D02*
Y400788D01*
G01X481299D02*
Y412599D01*
G01X500984D02*
Y400788D01*
G01X497047Y396851D02*
X485236D01*
G01X533465Y357481D02*
G03X529528Y353544I0J-3937D01*
G01X525591Y349607D02*
G03X529528Y353544I0J3937D01*
G01X525591Y349607D02*
X494094D01*
G01X525591D02*
G03X529528Y353544I0J3937D01*
G01X533465Y357481D02*
G03X529528Y353544I0J-3937D01*
G01X533465Y357481D02*
G03X529528Y353544I0J-3937D01*
G01X525591Y349607D02*
G03X529528Y353544I0J3937D01*
G01X604331Y357481D02*
X533465D01*
G01X485236Y416536D02*
G03X481299Y412599I0J-3937D01*
G01X500984D02*
G03X497047Y416536I-3937J0D01*
G01X485236D02*
X497047D01*
G01X529528Y572835D02*
G03X533465Y568898I3937J0D01*
G01X529528Y572835D02*
G03X525591Y576772I-3937J0D01*
G01D02*
X494094D01*
G01X529528Y572835D02*
G03X533465Y568898I3937J0D01*
G01X529528Y572835D02*
G03X525591Y576772I-3937J0D01*
G01X529528Y572835D02*
G03X533465Y568898I3937J0D01*
G01X529528Y572835D02*
G03X525591Y576772I-3937J0D01*
G01X533465Y568898D02*
X604331D01*
G01X533465Y592520D02*
G03X529528Y588583I0J-3937D01*
G01X525591Y584646D02*
G03X529528Y588583I0J3937D01*
G01X525591Y584646D02*
X494094D01*
G01X525591D02*
G03X529528Y588583I0J3937D01*
G01X533465Y592520D02*
G03X529528Y588583I0J-3937D01*
G01X533465Y592520D02*
G03X529528Y588583I0J-3937D01*
G01X525591Y584646D02*
G03X529528Y588583I0J3937D01*
G01X485236Y651576D02*
G03X481299Y647639I0J-3937D01*
G01X500984D02*
G03X497047Y651576I-3937J0D01*
G01Y631891D02*
G03X500984Y635828I0J3937D01*
G01X481299D02*
G03X485236Y631891I3937J0D01*
G01X475000Y647639D02*
Y635828D01*
G01X481299D02*
Y647639D01*
G01X500984D02*
Y635828D01*
G01X497047Y631891D02*
X485236D01*
G01Y651576D02*
X497047D01*
G01X604331Y592520D02*
X533465D01*
G01X652559Y39764D02*
G03X656496Y43701I0J3937D01*
G01X636811D02*
G03X640748Y39764I3937J0D01*
G01X652559D02*
X640748D01*
G01Y59449D02*
G03X636811Y55512I0J-3937D01*
G01X656496D02*
G03X652559Y59449I-3937J0D01*
G01X656496Y55512D02*
Y43701D01*
G01X636811D02*
Y55512D01*
G01X640748Y59449D02*
X652559D01*
G01X604331Y98819D02*
G03X608268Y102756I0J3937D01*
G01X612205Y106693D02*
G03X608268Y102756I0J-3937D01*
G01X612205Y106693D02*
G03X608268Y102756I0J-3937D01*
G01X604331Y98819D02*
G03X608268Y102756I0J3937D01*
G01X604331Y98819D02*
G03X608268Y102756I0J3937D01*
G01X612205Y106693D02*
G03X608268Y102756I0J-3937D01*
G01X612205Y106693D02*
X643701D01*
G01X612205D02*
X751969D01*
G01X608268Y118504D02*
G03X604331Y122441I-3937J0D01*
G01X608268Y118504D02*
G03X612205Y114567I3937J0D01*
G01D02*
X643701D01*
G01X608268Y118504D02*
G03X604331Y122441I-3937J0D01*
G01X608268Y118504D02*
G03X612205Y114567I3937J0D01*
G01X608268Y118504D02*
G03X604331Y122441I-3937J0D01*
G01X608268Y118504D02*
G03X612205Y114567I3937J0D01*
G01X751969D02*
X612205D01*
G01X652559Y274804D02*
G03X656496Y278741I0J3937D01*
G01X636811D02*
G03X640748Y274804I3937J0D01*
G01X656496Y290552D02*
Y278741D01*
G01X636811D02*
Y290552D01*
G01X652559Y274804D02*
X640748D01*
G01Y294489D02*
G03X636811Y290552I0J-3937D01*
G01X656496D02*
G03X652559Y294489I-3937J0D01*
G01X640748D02*
X652559D01*
G01X604331Y333859D02*
G03X608268Y337796I0J3937D01*
G01X612205Y341733D02*
G03X608268Y337796I0J-3937D01*
G01X612205Y341733D02*
X643701D01*
G01X612205D02*
G03X608268Y337796I0J-3937D01*
G01X604331Y333859D02*
G03X608268Y337796I0J3937D01*
G01X604331Y333859D02*
G03X608268Y337796I0J3937D01*
G01X612205Y341733D02*
G03X608268Y337796I0J-3937D01*
G01X612205Y341733D02*
X751969D01*
G01X608268Y353544D02*
G03X604331Y357481I-3937J0D01*
G01X608268Y353544D02*
G03X612205Y349607I3937J0D01*
G01D02*
X643701D01*
G01X608268Y353544D02*
G03X604331Y357481I-3937J0D01*
G01X608268Y353544D02*
G03X612205Y349607I3937J0D01*
G01X608268Y353544D02*
G03X604331Y357481I-3937J0D01*
G01X608268Y353544D02*
G03X612205Y349607I3937J0D01*
G01X751969D02*
X612205D01*
G01X652559Y509843D02*
G03X656496Y513780I0J3937D01*
G01X636811D02*
G03X640748Y509843I3937J0D01*
G01Y529528D02*
G03X636811Y525591I0J-3937D01*
G01X656496D02*
G03X652559Y529528I-3937J0D01*
G01X656496Y525591D02*
Y513780D01*
G01X636811D02*
Y525591D01*
G01X640748Y529528D02*
X652559D01*
G01Y509843D02*
X640748D01*
G01X604331Y568898D02*
G03X608268Y572835I0J3937D01*
G01X612205Y576772D02*
G03X608268Y572835I0J-3937D01*
G01X612205Y576772D02*
X643701D01*
G01X612205D02*
G03X608268Y572835I0J-3937D01*
G01X604331Y568898D02*
G03X608268Y572835I0J3937D01*
G01X604331Y568898D02*
G03X608268Y572835I0J3937D01*
G01X612205Y576772D02*
G03X608268Y572835I0J-3937D01*
G01X612205Y576772D02*
X751969D01*
G01X608268Y588583D02*
G03X604331Y592520I-3937J0D01*
G01X608268Y588583D02*
G03X612205Y584646I3937J0D01*
G01D02*
X643701D01*
G01X608268Y588583D02*
G03X604331Y592520I-3937J0D01*
G01X608268Y588583D02*
G03X612205Y584646I3937J0D01*
G01X608268Y588583D02*
G03X604331Y592520I-3937J0D01*
G01X608268Y588583D02*
G03X612205Y584646I3937J0D01*
G01X751969D02*
X612205D01*
G01X704528Y39764D02*
G03X708465Y43701I0J3937D01*
G01X688780D02*
G03X692717Y39764I3937J0D01*
G01X678543D02*
G03X682480Y43701I0J3937D01*
G01X662795D02*
G03X666732Y39764I3937J0D01*
G01X678543D02*
X666732D01*
G01X704528D02*
X692717D01*
G01X690748Y29331D02*
G03X683268I-3740J0D01*
G01X690748Y1969D02*
Y29331D01*
G01X681299Y0D02*
X683268Y1969D01*
G01D02*
Y29331D01*
G01X690748Y1969D02*
X692717Y0D01*
G01X732874D02*
X692717D01*
G01Y59449D02*
G03X688780Y55512I0J-3937D01*
G01X708465D02*
G03X704528Y59449I-3937J0D01*
G01X682480Y55512D02*
G03X678543Y59449I-3937J0D01*
G01X666732D02*
G03X662795Y55512I0J-3937D01*
G01X708465D02*
Y43701D01*
G01X688780D02*
Y55512D01*
G01X682480D02*
Y43701D01*
G01X662795D02*
Y55512D01*
G01X692717Y59449D02*
X704528D01*
G01X666732D02*
X678543D01*
G01X697441Y114567D02*
G03Y106693I0J-3937D01*
G01X666732D02*
G03Y114567I0J3937D01*
G01X704528Y274804D02*
G03X708465Y278741I0J3937D01*
G01X688780D02*
G03X692717Y274804I3937J0D01*
G01X678543D02*
G03X682480Y278741I0J3937D01*
G01X662795D02*
G03X666732Y274804I3937J0D01*
G01X708465Y290552D02*
Y278741D01*
G01X688780D02*
Y290552D01*
G01X682480D02*
Y278741D01*
G01X662795D02*
Y290552D01*
G01X678543Y274804D02*
X666732D01*
G01X704528D02*
X692717D01*
G01X690748Y264370D02*
G03X683268I-3740J0D01*
G01X690748Y237008D02*
Y264370D01*
G01X681299Y235040D02*
X683268Y237008D01*
G01D02*
Y264370D01*
G01X690748Y237008D02*
X692717Y235040D01*
G01X732874D02*
X692717D01*
G01Y294489D02*
G03X688780Y290552I0J-3937D01*
G01X708465D02*
G03X704528Y294489I-3937J0D01*
G01X682480Y290552D02*
G03X678543Y294489I-3937J0D01*
G01X666732D02*
G03X662795Y290552I0J-3937D01*
G01X692717Y294489D02*
X704528D01*
G01X666732D02*
X678543D01*
G01X697441Y349607D02*
G03Y341733I0J-3937D01*
G01X666732D02*
G03Y349607I0J3937D01*
G01X704528Y509843D02*
G03X708465Y513780I0J3937D01*
G01X688780D02*
G03X692717Y509843I3937J0D01*
G01Y529528D02*
G03X688780Y525591I0J-3937D01*
G01X708465D02*
G03X704528Y529528I-3937J0D01*
G01X682480Y525591D02*
G03X678543Y529528I-3937J0D01*
G01Y509843D02*
G03X682480Y513780I0J3937D01*
G01X662795D02*
G03X666732Y509843I3937J0D01*
G01Y529528D02*
G03X662795Y525591I0J-3937D01*
G01X708465D02*
Y513780D01*
G01X688780D02*
Y525591D01*
G01X682480D02*
Y513780D01*
G01X662795D02*
Y525591D01*
G01X692717Y529528D02*
X704528D01*
G01X666732D02*
X678543D01*
G01Y509843D02*
X666732D01*
G01X704528D02*
X692717D01*
G01X690748Y499410D02*
G03X683268I-3740J0D01*
G01X690748Y472048D02*
Y499410D01*
G01X681299Y470079D02*
X683268Y472048D01*
G01D02*
Y499410D01*
G01X690748Y472048D02*
X692717Y470079D01*
G01X732874D02*
X692717D01*
G01X697441Y584646D02*
G03Y576772I0J-3937D01*
G01X666732D02*
G03Y584646I0J3937D01*
G01X734843Y1969D02*
Y59941D01*
G01D02*
Y33858D01*
G01X732874Y0D02*
X734843Y1969D01*
G01X762744Y17317D02*
G03I-4292J0D01*
G01X775591Y553149D02*
Y15000D01*
G01X760591Y0D02*
G03X775591Y15000I0J15000D01*
G01X742717Y0D02*
Y56004D01*
G01Y0D02*
X760591D01*
G01X755906Y102756D02*
G03X751969Y106693I-3937J0D01*
G01Y63878D02*
G03X755906Y67815I0J3937D01*
G01X738780Y63878D02*
G03X734843Y59941I0J-3937D01*
G01X755906Y102756D02*
Y67815D01*
G01X751969Y63878D02*
X738780D01*
G01X763780Y152761D02*
Y98517D01*
G01Y67822D02*
Y67803D01*
G01X751969Y56004D02*
X742717D01*
G01X751969D02*
G03X763780Y67815I0J11811D01*
G01D02*
G03X755906I-3937J0D01*
G01Y98524D02*
G03X763780I3937J0D01*
G01X751969Y114567D02*
G03X755906Y118504I0J3937D01*
G01D02*
Y183465D01*
G01X763780Y152756D02*
G03X755906I-3937J0D01*
G01Y183465D02*
G03X751969Y187402I-3937J0D01*
G01X734843Y191339D02*
G03X738780Y187402I3937J0D01*
G01X751969D02*
X738780D01*
G01X734843Y219292D02*
X732874Y221260D01*
G01X734843Y219292D02*
Y191339D01*
G01X755906Y183465D02*
G03X763780I3937J0D01*
G01Y302855D02*
Y183460D01*
G01X734843Y237008D02*
Y294981D01*
G01D02*
Y268898D01*
G01X732874Y235040D02*
X734843Y237008D01*
G01X755906Y337796D02*
G03X751969Y341733I-3937J0D01*
G01Y298918D02*
G03X755906Y302855I0J3937D01*
G01X738780Y298918D02*
G03X734843Y294981I0J-3937D01*
G01X755906Y337796D02*
Y302855D01*
G01X751969Y298918D02*
X738780D01*
G01X763780Y387796D02*
Y333559D01*
G01Y302855D02*
G03X755906I-3937J0D01*
G01Y333563D02*
G03X763780I3937J0D01*
G01X751969Y349607D02*
G03X755906Y353544I0J3937D01*
G01D02*
Y418504D01*
G01X763780Y387796D02*
G03X755906I-3937J0D01*
G01Y418504D02*
G03X751969Y422441I-3937J0D01*
G01X734843Y426378D02*
G03X738780Y422441I3937J0D01*
G01X751969D02*
X738780D01*
G01X734843Y454331D02*
X732874Y456300D01*
G01X734843Y454331D02*
Y426378D01*
G01X763780Y537894D02*
Y418504D01*
G01X755906Y418505D02*
G03X763780I3937J0D01*
G01X734843Y472048D02*
Y530020D01*
G01D02*
Y503937D01*
G01X732874Y470079D02*
X734843Y472048D01*
G01X755906Y572835D02*
G03X751969Y576772I-3937J0D01*
G01Y533957D02*
G03X755906Y537894I0J3937D01*
G01X738780Y533957D02*
G03X734843Y530020I0J-3937D01*
G01X755906Y572835D02*
Y537894D01*
G01X751969Y533957D02*
X738780D01*
G01X751969Y584646D02*
G03X755906Y588583I0J3937D01*
G01D02*
Y653544D01*
G01X775591Y561023D02*
G03Y553149I0J-3937D01*
G01X763780Y537894D02*
G03X755906I-3937J0D01*
G01Y568603D02*
G03X763780I3937J0D01*
G01X775591Y676339D02*
Y561023D01*
G01X763780Y622835D02*
Y568603D01*
G01Y622835D02*
G03X755906I-3937J0D01*
G01Y653544D02*
G03X763780I3937J0D01*
G01X755906D02*
G03X751969Y657481I-3937J0D01*
G01X734843Y661418D02*
G03X738780Y657481I3937J0D01*
G01X751969D02*
X738780D01*
G01X734843Y689371D02*
X732874Y691339D01*
G01X734843Y689371D02*
Y661418D01*
G01X760014Y677788D02*
G03I-4292J0D01*
G01X775591Y676339D02*
G03X760591Y691339I-15000J0D01*
G01X751969Y665355D02*
X742717D01*
G01X763780Y653544D02*
G03X751969Y665355I-11811J0D01*
G01X742717Y691339D02*
X760591D01*
G01X742717Y665355D02*
Y691339D01*
G54D12*
G01X32789Y26060D02*
Y23920D01*
G01X34139Y25500D02*
Y23920D01*
G01X34783Y28054D02*
X32789Y26060D01*
G01X36133Y27494D02*
X34139Y25500D01*
G01X34783Y33330D02*
Y28054D01*
G01X36133Y32770D02*
Y27494D01*
G01X38233Y36780D02*
X34783Y33330D01*
G01X39583Y36220D02*
X36133Y32770D01*
G01X38233Y56890D02*
Y36780D01*
G01X39583Y57450D02*
Y36220D01*
G01X34139Y25500D02*
Y23920D01*
G01X32789Y26060D02*
Y23920D01*
G01X36133Y27494D02*
X34139Y25500D01*
G01X34783Y28054D02*
X32789Y26060D01*
G01X36133Y32770D02*
Y27494D01*
G01X34783Y33330D02*
Y28054D01*
G01X39583Y36220D02*
X36133Y32770D01*
G01X38233Y36780D02*
X34783Y33330D01*
G01X39583Y57450D02*
Y36220D01*
G01X38233Y56890D02*
Y36780D01*
G01X34783Y60340D02*
X38233Y56890D01*
G01X36133Y60900D02*
X39583Y57450D01*
G01X34783Y67040D02*
Y60340D01*
G01X36133Y67600D02*
Y60900D01*
G01X31033Y70790D02*
X34783Y67040D01*
G01X32383Y71350D02*
X36133Y67600D01*
G01X31033Y86200D02*
Y70790D01*
G01X32383Y85640D02*
Y71350D01*
G01X32233Y87400D02*
X31033Y86200D01*
G01X33343Y86600D02*
X32383Y85640D01*
G01X36133Y60900D02*
X39583Y57450D01*
G01X34783Y60340D02*
X38233Y56890D01*
G01X36133Y67600D02*
Y60900D01*
G01X34783Y67040D02*
Y60340D01*
G01X32383Y71350D02*
X36133Y67600D01*
G01X31033Y70790D02*
X34783Y67040D01*
G01X32383Y85640D02*
Y71350D01*
G01X31033Y86200D02*
Y70790D01*
G01X33343Y86600D02*
X32383Y85640D01*
G01X32233Y87400D02*
X31033Y86200D01*
G01X46783Y70900D02*
X50533Y67150D01*
G01X46783Y86200D02*
Y70900D01*
G01X47983Y87400D02*
X46783Y86200D01*
G01Y70900D02*
X50533Y67150D01*
G01X46783Y86200D02*
Y70900D01*
G01X47983Y87400D02*
X46783Y86200D01*
G01X80034Y57900D02*
Y23920D01*
G01X81384Y57340D02*
Y23920D01*
G01Y57340D02*
Y23920D01*
G01X80034Y57900D02*
Y23920D01*
G01X95782Y37838D02*
Y23920D01*
G01X97132Y37278D02*
Y23920D01*
G01X97122Y39178D02*
X95782Y37838D01*
G01X97682Y37828D02*
X97132Y37278D01*
G01X97844Y39728D02*
X97294Y39178D01*
G01X99194Y39168D02*
X97854Y37828D01*
G01X97844Y40828D02*
Y39728D01*
G01X99194Y41388D02*
Y39168D01*
G01X97294Y41378D02*
X97844Y40828D01*
G01X97854Y42728D02*
X99194Y41388D01*
G01X95060Y41378D02*
X97294D01*
G01X93720Y42718D02*
X95060Y41378D01*
G01X97132Y37278D02*
Y23920D01*
G01X95782Y37838D02*
Y23920D01*
G01X97682Y37828D02*
X97132Y37278D01*
G01X97122Y39178D02*
X95782Y37838D01*
G01X99194Y39168D02*
X97854Y37828D01*
G01X97844Y39728D02*
X97294Y39178D01*
G01X99194Y41388D02*
Y39168D01*
G01X97844Y40828D02*
Y39728D01*
G01X97854Y42728D02*
X99194Y41388D01*
G01X97294Y41378D02*
X97844Y40828D01*
G01X95060Y41378D02*
X97294D01*
G01X93720Y42718D02*
X95060Y41378D01*
G01X65636Y59503D02*
Y23920D01*
G01X64286Y60063D02*
Y23920D01*
G01X48538Y60005D02*
Y23920D01*
G01X49888Y59445D02*
Y23920D01*
G01Y59445D02*
Y23920D01*
G01X48538Y60005D02*
Y23920D01*
G01X64286Y60063D02*
Y23920D01*
G01X65636Y59503D02*
Y23920D01*
G01X82023Y59889D02*
X80034Y57900D01*
G01X83373Y59329D02*
X81384Y57340D01*
G01X82023Y67150D02*
Y59889D01*
G01X83373Y67710D02*
Y59329D01*
G01X78273Y70900D02*
X82023Y67150D01*
G01X79623Y71460D02*
X83373Y67710D01*
G01X78273Y86200D02*
Y70900D01*
G01X79623Y85640D02*
Y71460D01*
G01X79473Y87400D02*
X78273Y86200D01*
G01X80583Y86600D02*
X79623Y85640D01*
G01X83373Y59329D02*
X81384Y57340D01*
G01X82023Y59889D02*
X80034Y57900D01*
G01X83373Y67710D02*
Y59329D01*
G01X82023Y67150D02*
Y59889D01*
G01X79623Y71460D02*
X83373Y67710D01*
G01X78273Y70900D02*
X82023Y67150D01*
G01X79623Y85640D02*
Y71460D01*
G01X78273Y86200D02*
Y70900D01*
G01X80583Y86600D02*
X79623Y85640D01*
G01X79473Y87400D02*
X78273Y86200D01*
G01X95620Y42728D02*
X97854D01*
G01X95070Y43278D02*
X95620Y42728D01*
G01X93720Y44938D02*
Y42718D01*
G01X95070Y44378D02*
Y43278D01*
G01X95060Y46278D02*
X93720Y44938D01*
G01X95620Y44928D02*
X95070Y44378D01*
G01X97294Y46278D02*
X95060D01*
G01X97854Y44928D02*
X95620D01*
G01X97844Y46828D02*
X97294Y46278D01*
G01X99194Y46268D02*
X97854Y44928D01*
G01X97844Y47928D02*
Y46828D01*
G01X99194Y48488D02*
Y46268D01*
G01X97294Y48478D02*
X97844Y47928D01*
G01X97854Y49828D02*
X99194Y48488D01*
G01X95060Y48478D02*
X97294D01*
G01X95620Y49828D02*
X97854D01*
G01X93720Y49818D02*
X95060Y48478D01*
G01X95070Y50378D02*
X95620Y49828D01*
G01X93720Y52038D02*
Y49818D01*
G01X95070Y51478D02*
Y50378D01*
G01X95060Y53378D02*
X93720Y52038D01*
G01X95620Y52028D02*
X95070Y51478D01*
G01X97294Y53378D02*
X95060D01*
G01X97854Y52028D02*
X95620D01*
G01X97844Y53928D02*
X97294Y53378D01*
G01X99194Y53368D02*
X97854Y52028D01*
G01X97844Y55028D02*
Y53928D01*
G01X99194Y55588D02*
Y53368D01*
G01X97294Y55578D02*
X97844Y55028D01*
G01X97854Y56928D02*
X99194Y55588D01*
G01X95060Y55578D02*
X97294D01*
G01X95620Y56928D02*
X97854D01*
G01X93720Y56918D02*
X95060Y55578D01*
G01X95070Y57478D02*
X95620Y56928D01*
G01X93720Y59030D02*
Y56918D01*
G01X95070Y58470D02*
Y57478D01*
G01X97768Y63078D02*
X93720Y59030D01*
G01X99118Y62518D02*
X95070Y58470D01*
G01X97768Y67150D02*
Y63078D01*
G01X99118Y67710D02*
Y62518D01*
G01X94018Y70900D02*
X97768Y67150D01*
G01X95368Y71460D02*
X99118Y67710D01*
G01X94018Y86200D02*
Y70900D01*
G01X95368Y85640D02*
Y71460D01*
G01X95218Y87400D02*
X94018Y86200D01*
G01X96328Y86600D02*
X95368Y85640D01*
G01X95620Y42728D02*
X97854D01*
G01X95070Y43278D02*
X95620Y42728D01*
G01X95070Y44378D02*
Y43278D01*
G01X93720Y44938D02*
Y42718D01*
G01X95620Y44928D02*
X95070Y44378D01*
G01X95060Y46278D02*
X93720Y44938D01*
G01X97854Y44928D02*
X95620D01*
G01X97294Y46278D02*
X95060D01*
G01X99194Y46268D02*
X97854Y44928D01*
G01X97844Y46828D02*
X97294Y46278D01*
G01X99194Y48488D02*
Y46268D01*
G01X97844Y47928D02*
Y46828D01*
G01X97854Y49828D02*
X99194Y48488D01*
G01X97294Y48478D02*
X97844Y47928D01*
G01X95620Y49828D02*
X97854D01*
G01X95060Y48478D02*
X97294D01*
G01X95070Y50378D02*
X95620Y49828D01*
G01X93720Y49818D02*
X95060Y48478D01*
G01X95070Y51478D02*
Y50378D01*
G01X93720Y52038D02*
Y49818D01*
G01X95620Y52028D02*
X95070Y51478D01*
G01X95060Y53378D02*
X93720Y52038D01*
G01X97854Y52028D02*
X95620D01*
G01X97294Y53378D02*
X95060D01*
G01X99194Y53368D02*
X97854Y52028D01*
G01X97844Y53928D02*
X97294Y53378D01*
G01X99194Y55588D02*
Y53368D01*
G01X97844Y55028D02*
Y53928D01*
G01X97854Y56928D02*
X99194Y55588D01*
G01X97294Y55578D02*
X97844Y55028D01*
G01X95620Y56928D02*
X97854D01*
G01X95060Y55578D02*
X97294D01*
G01X95070Y57478D02*
X95620Y56928D01*
G01X93720Y56918D02*
X95060Y55578D01*
G01X95070Y58470D02*
Y57478D01*
G01X93720Y59030D02*
Y56918D01*
G01X99118Y62518D02*
X95070Y58470D01*
G01X97768Y63078D02*
X93720Y59030D01*
G01X99118Y67710D02*
Y62518D01*
G01X97768Y67150D02*
Y63078D01*
G01X95368Y71460D02*
X99118Y67710D01*
G01X94018Y70900D02*
X97768Y67150D01*
G01X95368Y85640D02*
Y71460D01*
G01X94018Y86200D02*
Y70900D01*
G01X96328Y86600D02*
X95368Y85640D01*
G01X95218Y87400D02*
X94018Y86200D01*
G01X67628Y61495D02*
X65636Y59503D01*
G01X66278Y62055D02*
X64286Y60063D01*
G01X67628Y67710D02*
Y61495D01*
G01X66278Y67150D02*
Y62055D01*
G01X63878Y71460D02*
X67628Y67710D01*
G01X62528Y70900D02*
X66278Y67150D01*
G01X63878Y85640D02*
Y71460D01*
G01X62528Y86200D02*
Y70900D01*
G01X64838Y86600D02*
X63878Y85640D01*
G01X63728Y87400D02*
X62528Y86200D01*
G01X50533Y62000D02*
X48538Y60005D01*
G01X51883Y61440D02*
X49888Y59445D01*
G01X50533Y67150D02*
Y62000D01*
G01X51883Y67710D02*
Y61440D01*
G01X48133Y71460D02*
X51883Y67710D01*
G01X48133Y85640D02*
Y71460D01*
G01X49093Y86600D02*
X48133Y85640D01*
G01X51883Y61440D02*
X49888Y59445D01*
G01X50533Y62000D02*
X48538Y60005D01*
G01X51883Y67710D02*
Y61440D01*
G01X50533Y67150D02*
Y62000D01*
G01X48133Y71460D02*
X51883Y67710D01*
G01X48133Y85640D02*
Y71460D01*
G01X49093Y86600D02*
X48133Y85640D01*
G01X66278Y62055D02*
X64286Y60063D01*
G01X67628Y61495D02*
X65636Y59503D01*
G01X66278Y67150D02*
Y62055D01*
G01X67628Y67710D02*
Y61495D01*
G01X62528Y70900D02*
X66278Y67150D01*
G01X63878Y71460D02*
X67628Y67710D01*
G01X62528Y86200D02*
Y70900D01*
G01X63878Y85640D02*
Y71460D01*
G01X63728Y87400D02*
X62528Y86200D01*
G01X64838Y86600D02*
X63878Y85640D01*
G01X128628Y37048D02*
Y23920D01*
G01X127278Y37608D02*
Y23920D01*
G01X129178Y37598D02*
X128628Y37048D01*
G01X128618Y38948D02*
X127278Y37608D01*
G01X130726Y38938D02*
X129386Y37598D01*
G01X129376Y39498D02*
X128826Y38948D01*
G01X130726Y41158D02*
Y38938D01*
G01X129376Y40598D02*
Y39498D01*
G01X129386Y42498D02*
X130726Y41158D01*
G01X128826Y41148D02*
X129376Y40598D01*
G01X126520Y41148D02*
X128826D01*
G01X125180Y42488D02*
X126520Y41148D01*
G01X143026Y37463D02*
Y23920D01*
G01X144376Y36903D02*
Y23920D01*
G01X144366Y38803D02*
X143026Y37463D01*
G01X144926Y37453D02*
X144376Y36903D01*
G01X145112Y39353D02*
X144562Y38803D01*
G01X146462Y38793D02*
X145122Y37453D01*
G01X145112Y40453D02*
Y39353D01*
G01X146462Y41013D02*
Y38793D01*
G01X144562Y41003D02*
X145112Y40453D01*
G01X145122Y42353D02*
X146462Y41013D01*
G01X142280Y41003D02*
X144562D01*
G01X140940Y42343D02*
X142280Y41003D01*
G01X144376Y36903D02*
Y23920D01*
G01X143026Y37463D02*
Y23920D01*
G01X144926Y37453D02*
X144376Y36903D01*
G01X144366Y38803D02*
X143026Y37463D01*
G01X146462Y38793D02*
X145122Y37453D01*
G01X145112Y39353D02*
X144562Y38803D01*
G01X146462Y41013D02*
Y38793D01*
G01X145112Y40453D02*
Y39353D01*
G01X145122Y42353D02*
X146462Y41013D01*
G01X144562Y41003D02*
X145112Y40453D01*
G01X142280Y41003D02*
X144562D01*
G01X140940Y42343D02*
X142280Y41003D01*
G01X158533Y57510D02*
Y24000D01*
G01X159883Y56950D02*
Y24050D01*
G01Y56950D02*
Y24050D01*
G01X158533Y57510D02*
Y24000D01*
G01X111530Y36833D02*
Y23920D01*
G01X112880Y36273D02*
Y23920D01*
G01X112870Y38173D02*
X111530Y36833D01*
G01X113430Y36823D02*
X112880Y36273D01*
G01X113580Y38723D02*
X113030Y38173D01*
G01X114930Y38163D02*
X113590Y36823D01*
G01X113580Y39823D02*
Y38723D01*
G01X114930Y40383D02*
Y38163D01*
G01X113030Y40373D02*
X113580Y39823D01*
G01X113590Y41723D02*
X114930Y40383D01*
G01X110820Y40373D02*
X113030D01*
G01X111380Y41723D02*
X113590D01*
G01X109480Y41713D02*
X110820Y40373D01*
G01X110830Y42273D02*
X111380Y41723D01*
G01X109480Y43933D02*
Y41713D01*
G01X112880Y36273D02*
Y23920D01*
G01X111530Y36833D02*
Y23920D01*
G01X113430Y36823D02*
X112880Y36273D01*
G01X112870Y38173D02*
X111530Y36833D01*
G01X114930Y38163D02*
X113590Y36823D01*
G01X113580Y38723D02*
X113030Y38173D01*
G01X114930Y40383D02*
Y38163D01*
G01X113580Y39823D02*
Y38723D01*
G01X113590Y41723D02*
X114930Y40383D01*
G01X113030Y40373D02*
X113580Y39823D01*
G01X111380Y41723D02*
X113590D01*
G01X110820Y40373D02*
X113030D01*
G01X110830Y42273D02*
X111380Y41723D01*
G01X109480Y41713D02*
X110820Y40373D01*
G01X109480Y43933D02*
Y41713D01*
G01X127278Y37608D02*
Y23920D01*
G01X128628Y37048D02*
Y23920D01*
G01X128618Y38948D02*
X127278Y37608D01*
G01X129178Y37598D02*
X128628Y37048D01*
G01X129376Y39498D02*
X128826Y38948D01*
G01X130726Y38938D02*
X129386Y37598D01*
G01X129376Y40598D02*
Y39498D01*
G01X130726Y41158D02*
Y38938D01*
G01X128826Y41148D02*
X129376Y40598D01*
G01X129386Y42498D02*
X130726Y41158D01*
G01X126520Y41148D02*
X128826D01*
G01X125180Y42488D02*
X126520Y41148D01*
G01X127080Y42498D02*
X129386D01*
G01X126530Y43048D02*
X127080Y42498D01*
G01X126530Y44148D02*
Y43048D01*
G01X125180Y44708D02*
Y42488D01*
G01X127080Y44698D02*
X126530Y44148D01*
G01X126520Y46048D02*
X125180Y44708D01*
G01X129386Y44698D02*
X127080D01*
G01X128826Y46048D02*
X126520D01*
G01X130726Y46038D02*
X129386Y44698D01*
G01X129376Y46598D02*
X128826Y46048D01*
G01X130726Y48258D02*
Y46038D01*
G01X129376Y47698D02*
Y46598D01*
G01X129386Y49598D02*
X130726Y48258D01*
G01X128826Y48248D02*
X129376Y47698D01*
G01X127080Y49598D02*
X129386D01*
G01X126520Y48248D02*
X128826D01*
G01X126530Y50148D02*
X127080Y49598D01*
G01X125180Y49588D02*
X126520Y48248D01*
G01X126530Y51248D02*
Y50148D01*
G01X125180Y51808D02*
Y49588D01*
G01X127080Y51798D02*
X126530Y51248D01*
G01X126520Y53148D02*
X125180Y51808D01*
G01X129386Y51798D02*
X127080D01*
G01X128826Y53148D02*
X126520D01*
G01X130726Y53138D02*
X129386Y51798D01*
G01X129376Y53698D02*
X128826Y53148D01*
G01X130726Y55358D02*
Y53138D01*
G01X129376Y54798D02*
Y53698D01*
G01X129386Y56698D02*
X130726Y55358D01*
G01X128826Y55348D02*
X129376Y54798D01*
G01X127080Y56698D02*
X129386D01*
G01X126520Y55348D02*
X128826D01*
G01X126530Y57248D02*
X127080Y56698D01*
G01X125180Y56688D02*
X126520Y55348D01*
G01X126530Y58210D02*
Y57248D01*
G01X125180Y58770D02*
Y56688D01*
G01X130608Y62288D02*
X126530Y58210D01*
G01X129258Y62848D02*
X125180Y58770D01*
G01X130608Y67710D02*
Y62288D01*
G01X129258Y67150D02*
Y62848D01*
G01X126858Y71460D02*
X130608Y67710D01*
G01X125508Y70900D02*
X129258Y67150D01*
G01X126858Y85640D02*
Y71460D01*
G01X125508Y86200D02*
Y70900D01*
G01X127818Y86600D02*
X126858Y85640D01*
G01X126708Y87400D02*
X125508Y86200D01*
G01X142840Y42353D02*
X145122D01*
G01X142290Y42903D02*
X142840Y42353D01*
G01X140940Y44563D02*
Y42343D01*
G01X142290Y44003D02*
Y42903D01*
G01X142280Y45903D02*
X140940Y44563D01*
G01X142840Y44553D02*
X142290Y44003D01*
G01X144562Y45903D02*
X142280D01*
G01X145122Y44553D02*
X142840D01*
G01X145112Y46453D02*
X144562Y45903D01*
G01X146462Y45893D02*
X145122Y44553D01*
G01X145112Y47553D02*
Y46453D01*
G01X146462Y48113D02*
Y45893D01*
G01X144562Y48103D02*
X145112Y47553D01*
G01X145122Y49453D02*
X146462Y48113D01*
G01X142280Y48103D02*
X144562D01*
G01X142840Y49453D02*
X145122D01*
G01X140940Y49443D02*
X142280Y48103D01*
G01X142290Y50003D02*
X142840Y49453D01*
G01X140940Y51663D02*
Y49443D01*
G01X142290Y51103D02*
Y50003D01*
G01X142280Y53003D02*
X140940Y51663D01*
G01X142840Y51653D02*
X142290Y51103D01*
G01X144562Y53003D02*
X142280D01*
G01X145122Y51653D02*
X142840D01*
G01X145112Y53553D02*
X144562Y53003D01*
G01X146462Y52993D02*
X145122Y51653D01*
G01X145112Y54653D02*
Y53553D01*
G01X146462Y55213D02*
Y52993D01*
G01X144562Y55203D02*
X145112Y54653D01*
G01X145122Y56553D02*
X146462Y55213D01*
G01X142280Y55203D02*
X144562D01*
G01X142840Y56553D02*
X145122D01*
G01X140940Y56543D02*
X142280Y55203D01*
G01X142290Y57103D02*
X142840Y56553D01*
G01X140940Y58640D02*
Y56543D01*
G01X142290Y58080D02*
Y57103D01*
G01X145003Y62703D02*
X140940Y58640D01*
G01X146353Y62143D02*
X142290Y58080D01*
G01X145003Y67150D02*
Y62703D01*
G01X146353Y67710D02*
Y62143D01*
G01X141253Y70900D02*
X145003Y67150D01*
G01X142603Y71460D02*
X146353Y67710D01*
G01X141253Y86200D02*
Y70900D01*
G01X142603Y85640D02*
Y71460D01*
G01X142453Y87400D02*
X141253Y86200D01*
G01X143563Y86600D02*
X142603Y85640D01*
G01X142840Y42353D02*
X145122D01*
G01X142290Y42903D02*
X142840Y42353D01*
G01X142290Y44003D02*
Y42903D01*
G01X140940Y44563D02*
Y42343D01*
G01X142840Y44553D02*
X142290Y44003D01*
G01X142280Y45903D02*
X140940Y44563D01*
G01X145122Y44553D02*
X142840D01*
G01X144562Y45903D02*
X142280D01*
G01X146462Y45893D02*
X145122Y44553D01*
G01X145112Y46453D02*
X144562Y45903D01*
G01X146462Y48113D02*
Y45893D01*
G01X145112Y47553D02*
Y46453D01*
G01X145122Y49453D02*
X146462Y48113D01*
G01X144562Y48103D02*
X145112Y47553D01*
G01X142840Y49453D02*
X145122D01*
G01X142280Y48103D02*
X144562D01*
G01X142290Y50003D02*
X142840Y49453D01*
G01X140940Y49443D02*
X142280Y48103D01*
G01X142290Y51103D02*
Y50003D01*
G01X140940Y51663D02*
Y49443D01*
G01X142840Y51653D02*
X142290Y51103D01*
G01X142280Y53003D02*
X140940Y51663D01*
G01X145122Y51653D02*
X142840D01*
G01X144562Y53003D02*
X142280D01*
G01X146462Y52993D02*
X145122Y51653D01*
G01X145112Y53553D02*
X144562Y53003D01*
G01X146462Y55213D02*
Y52993D01*
G01X145112Y54653D02*
Y53553D01*
G01X145122Y56553D02*
X146462Y55213D01*
G01X144562Y55203D02*
X145112Y54653D01*
G01X142840Y56553D02*
X145122D01*
G01X142280Y55203D02*
X144562D01*
G01X142290Y57103D02*
X142840Y56553D01*
G01X140940Y56543D02*
X142280Y55203D01*
G01X142290Y58080D02*
Y57103D01*
G01X140940Y58640D02*
Y56543D01*
G01X146353Y62143D02*
X142290Y58080D01*
G01X145003Y62703D02*
X140940Y58640D01*
G01X146353Y67710D02*
Y62143D01*
G01X145003Y67150D02*
Y62703D01*
G01X142603Y71460D02*
X146353Y67710D01*
G01X141253Y70900D02*
X145003Y67150D01*
G01X142603Y85640D02*
Y71460D01*
G01X141253Y86200D02*
Y70900D01*
G01X143563Y86600D02*
X142603Y85640D01*
G01X142453Y87400D02*
X141253Y86200D01*
G01X160748Y59725D02*
X158533Y57510D01*
G01X162098Y59165D02*
X159883Y56950D01*
G01X160748Y67150D02*
Y59725D01*
G01X162098Y67710D02*
Y59165D01*
G01X156998Y70900D02*
X160748Y67150D01*
G01X158348Y71460D02*
X162098Y67710D01*
G01X156998Y85275D02*
Y70900D01*
G01X158348Y84715D02*
Y71460D01*
G01X159463Y87740D02*
X156998Y85275D01*
G01X159033Y85400D02*
X158348Y84715D01*
G01X162098Y59165D02*
X159883Y56950D01*
G01X160748Y59725D02*
X158533Y57510D01*
G01X162098Y67710D02*
Y59165D01*
G01X160748Y67150D02*
Y59725D01*
G01X158348Y71460D02*
X162098Y67710D01*
G01X156998Y70900D02*
X160748Y67150D01*
G01X158348Y84715D02*
Y71460D01*
G01X156998Y85275D02*
Y70900D01*
G01X159033Y85400D02*
X158348Y84715D01*
G01X159463Y87740D02*
X156998Y85275D01*
G01X110830Y43373D02*
Y42273D01*
G01X110820Y45273D02*
X109480Y43933D01*
G01X111380Y43923D02*
X110830Y43373D01*
G01X113030Y45273D02*
X110820D01*
G01X113590Y43923D02*
X111380D01*
G01X113580Y45823D02*
X113030Y45273D01*
G01X114930Y45263D02*
X113590Y43923D01*
G01X113580Y46923D02*
Y45823D01*
G01X114930Y47483D02*
Y45263D01*
G01X113030Y47473D02*
X113580Y46923D01*
G01X113590Y48823D02*
X114930Y47483D01*
G01X110820Y47473D02*
X113030D01*
G01X111380Y48823D02*
X113590D01*
G01X109480Y48813D02*
X110820Y47473D01*
G01X110830Y49373D02*
X111380Y48823D01*
G01X109480Y51033D02*
Y48813D01*
G01X110830Y50473D02*
Y49373D01*
G01X110820Y52373D02*
X109480Y51033D01*
G01X111380Y51023D02*
X110830Y50473D01*
G01X113030Y52373D02*
X110820D01*
G01X113590Y51023D02*
X111380D01*
G01X113580Y52923D02*
X113030Y52373D01*
G01X114930Y52363D02*
X113590Y51023D01*
G01X113580Y54023D02*
Y52923D01*
G01X114930Y54583D02*
Y52363D01*
G01X113030Y54573D02*
X113580Y54023D01*
G01X113590Y55923D02*
X114930Y54583D01*
G01X110820Y54573D02*
X113030D01*
G01X111380Y55923D02*
X113590D01*
G01X109480Y55913D02*
X110820Y54573D01*
G01X110830Y56473D02*
X111380Y55923D01*
G01X109480Y58120D02*
Y55913D01*
G01X110830Y57560D02*
Y56473D01*
G01X113513Y62153D02*
X109480Y58120D01*
G01X114863Y61593D02*
X110830Y57560D01*
G01X113513Y67150D02*
Y62153D01*
G01X114863Y67710D02*
Y61593D01*
G01X109763Y70900D02*
X113513Y67150D01*
G01X111113Y71460D02*
X114863Y67710D01*
G01X109763Y86200D02*
Y70900D01*
G01X111113Y85640D02*
Y71460D01*
G01X110963Y87400D02*
X109763Y86200D01*
G01X112073Y86600D02*
X111113Y85640D01*
G01X110830Y43373D02*
Y42273D01*
G01X111380Y43923D02*
X110830Y43373D01*
G01X110820Y45273D02*
X109480Y43933D01*
G01X113590Y43923D02*
X111380D01*
G01X113030Y45273D02*
X110820D01*
G01X114930Y45263D02*
X113590Y43923D01*
G01X113580Y45823D02*
X113030Y45273D01*
G01X114930Y47483D02*
Y45263D01*
G01X113580Y46923D02*
Y45823D01*
G01X113590Y48823D02*
X114930Y47483D01*
G01X113030Y47473D02*
X113580Y46923D01*
G01X111380Y48823D02*
X113590D01*
G01X110820Y47473D02*
X113030D01*
G01X110830Y49373D02*
X111380Y48823D01*
G01X109480Y48813D02*
X110820Y47473D01*
G01X110830Y50473D02*
Y49373D01*
G01X109480Y51033D02*
Y48813D01*
G01X111380Y51023D02*
X110830Y50473D01*
G01X110820Y52373D02*
X109480Y51033D01*
G01X113590Y51023D02*
X111380D01*
G01X113030Y52373D02*
X110820D01*
G01X114930Y52363D02*
X113590Y51023D01*
G01X113580Y52923D02*
X113030Y52373D01*
G01X114930Y54583D02*
Y52363D01*
G01X113580Y54023D02*
Y52923D01*
G01X113590Y55923D02*
X114930Y54583D01*
G01X113030Y54573D02*
X113580Y54023D01*
G01X111380Y55923D02*
X113590D01*
G01X110820Y54573D02*
X113030D01*
G01X110830Y56473D02*
X111380Y55923D01*
G01X109480Y55913D02*
X110820Y54573D01*
G01X110830Y57560D02*
Y56473D01*
G01X109480Y58120D02*
Y55913D01*
G01X114863Y61593D02*
X110830Y57560D01*
G01X113513Y62153D02*
X109480Y58120D01*
G01X114863Y67710D02*
Y61593D01*
G01X113513Y67150D02*
Y62153D01*
G01X111113Y71460D02*
X114863Y67710D01*
G01X109763Y70900D02*
X113513Y67150D01*
G01X111113Y85640D02*
Y71460D01*
G01X109763Y86200D02*
Y70900D01*
G01X112073Y86600D02*
X111113Y85640D01*
G01X110963Y87400D02*
X109763Y86200D01*
G01X127080Y42498D02*
X129386D01*
G01X126530Y43048D02*
X127080Y42498D01*
G01X125180Y44708D02*
Y42488D01*
G01X126530Y44148D02*
Y43048D01*
G01X126520Y46048D02*
X125180Y44708D01*
G01X127080Y44698D02*
X126530Y44148D01*
G01X128826Y46048D02*
X126520D01*
G01X129386Y44698D02*
X127080D01*
G01X129376Y46598D02*
X128826Y46048D01*
G01X130726Y46038D02*
X129386Y44698D01*
G01X129376Y47698D02*
Y46598D01*
G01X130726Y48258D02*
Y46038D01*
G01X128826Y48248D02*
X129376Y47698D01*
G01X129386Y49598D02*
X130726Y48258D01*
G01X126520Y48248D02*
X128826D01*
G01X127080Y49598D02*
X129386D01*
G01X125180Y49588D02*
X126520Y48248D01*
G01X126530Y50148D02*
X127080Y49598D01*
G01X125180Y51808D02*
Y49588D01*
G01X126530Y51248D02*
Y50148D01*
G01X126520Y53148D02*
X125180Y51808D01*
G01X127080Y51798D02*
X126530Y51248D01*
G01X128826Y53148D02*
X126520D01*
G01X129386Y51798D02*
X127080D01*
G01X129376Y53698D02*
X128826Y53148D01*
G01X130726Y53138D02*
X129386Y51798D01*
G01X129376Y54798D02*
Y53698D01*
G01X130726Y55358D02*
Y53138D01*
G01X128826Y55348D02*
X129376Y54798D01*
G01X129386Y56698D02*
X130726Y55358D01*
G01X126520Y55348D02*
X128826D01*
G01X127080Y56698D02*
X129386D01*
G01X125180Y56688D02*
X126520Y55348D01*
G01X126530Y57248D02*
X127080Y56698D01*
G01X125180Y58770D02*
Y56688D01*
G01X126530Y58210D02*
Y57248D01*
G01X129258Y62848D02*
X125180Y58770D01*
G01X130608Y62288D02*
X126530Y58210D01*
G01X129258Y67150D02*
Y62848D01*
G01X130608Y67710D02*
Y62288D01*
G01X125508Y70900D02*
X129258Y67150D01*
G01X126858Y71460D02*
X130608Y67710D01*
G01X125508Y86200D02*
Y70900D01*
G01X126858Y85640D02*
Y71460D01*
G01X126708Y87400D02*
X125508Y86200D01*
G01X127818Y86600D02*
X126858Y85640D01*
G01X221733Y56300D02*
Y23700D01*
G01X223083Y55740D02*
Y23950D01*
G01Y55740D02*
Y23950D01*
G01X221733Y56300D02*
Y23700D01*
G01X206018Y56600D02*
Y23920D01*
G01X207368Y56040D02*
Y23920D01*
G01Y56040D02*
Y23920D01*
G01X206018Y56600D02*
Y23920D01*
G01X223728Y58295D02*
X221733Y56300D01*
G01X225078Y57735D02*
X223083Y55740D01*
G01X223728Y67150D02*
Y58295D01*
G01X225078Y67710D02*
Y57735D01*
G01X219978Y70900D02*
X223728Y67150D01*
G01X221328Y71460D02*
X225078Y67710D01*
G01X219978Y87455D02*
Y70900D01*
G01X221328Y86895D02*
Y71460D01*
G01X220442Y87919D02*
X219978Y87455D01*
G01X222133Y87700D02*
X221328Y86895D01*
G01X225078Y57735D02*
X223083Y55740D01*
G01X223728Y58295D02*
X221733Y56300D01*
G01X225078Y67710D02*
Y57735D01*
G01X223728Y67150D02*
Y58295D01*
G01X221328Y71460D02*
X225078Y67710D01*
G01X219978Y70900D02*
X223728Y67150D01*
G01X221328Y86895D02*
Y71460D01*
G01X219978Y87455D02*
Y70900D01*
G01X222133Y87700D02*
X221328Y86895D01*
G01X220442Y87919D02*
X219978Y87455D01*
G01X207983Y58565D02*
X206018Y56600D01*
G01X209333Y58005D02*
X207368Y56040D01*
G01X207983Y67150D02*
Y58565D01*
G01X209333Y67710D02*
Y58005D01*
G01X204233Y70900D02*
X207983Y67150D01*
G01X205583Y71460D02*
X209333Y67710D01*
G01X204233Y86200D02*
Y70900D01*
G01X205583Y85640D02*
Y71460D01*
G01X205433Y87400D02*
X204233Y86200D01*
G01X206543Y86600D02*
X205583Y85640D01*
G01X209333Y58005D02*
X207368Y56040D01*
G01X207983Y58565D02*
X206018Y56600D01*
G01X209333Y67710D02*
Y58005D01*
G01X207983Y67150D02*
Y58565D01*
G01X205583Y71460D02*
X209333Y67710D01*
G01X204233Y70900D02*
X207983Y67150D01*
G01X205583Y85640D02*
Y71460D01*
G01X204233Y86200D02*
Y70900D01*
G01X206543Y86600D02*
X205583Y85640D01*
G01X205433Y87400D02*
X204233Y86200D01*
G01X269009Y31024D02*
Y23920D01*
G01X270359Y31584D02*
Y23920D01*
G01X265463Y34570D02*
X269009Y31024D01*
G01X266023Y35920D02*
X270359Y31584D01*
G01X257853Y34570D02*
X265463D01*
G01X258413Y35920D02*
X266023D01*
G01X251433Y40990D02*
X257853Y34570D01*
G01X252783Y41550D02*
X258413Y35920D01*
G01X251433Y59800D02*
Y40990D01*
G01X252783Y59240D02*
Y41550D01*
G01X270359Y31584D02*
Y23920D01*
G01X269009Y31024D02*
Y23920D01*
G01X266023Y35920D02*
X270359Y31584D01*
G01X265463Y34570D02*
X269009Y31024D01*
G01X258413Y35920D02*
X266023D01*
G01X257853Y34570D02*
X265463D01*
G01X252783Y41550D02*
X258413Y35920D01*
G01X251433Y40990D02*
X257853Y34570D01*
G01X252783Y59240D02*
Y41550D01*
G01X251433Y59800D02*
Y40990D01*
G01X284758Y33672D02*
Y23920D01*
G01X286108Y34232D02*
Y23920D01*
G01X283740Y34690D02*
X284758Y33672D01*
G01X284300Y36040D02*
X286108Y34232D01*
G01X274650Y34690D02*
X283740D01*
G01X275210Y36040D02*
X284300D01*
G01X273220Y36120D02*
X274650Y34690D01*
G01X274570Y36680D02*
X275210Y36040D01*
G01X273220Y38270D02*
Y36120D01*
G01X274570Y37710D02*
Y36680D01*
G01X276095Y41145D02*
X273220Y38270D01*
G01X277445Y40585D02*
X274570Y37710D01*
G01X276095Y60772D02*
Y41145D01*
G01X277445Y60212D02*
Y40585D01*
G01X286108Y34232D02*
Y23920D01*
G01X284758Y33672D02*
Y23920D01*
G01X284300Y36040D02*
X286108Y34232D01*
G01X283740Y34690D02*
X284758Y33672D01*
G01X275210Y36040D02*
X284300D01*
G01X274650Y34690D02*
X283740D01*
G01X274570Y36680D02*
X275210Y36040D01*
G01X273220Y36120D02*
X274650Y34690D01*
G01X274570Y37710D02*
Y36680D01*
G01X273220Y38270D02*
Y36120D01*
G01X277445Y40585D02*
X274570Y37710D01*
G01X276095Y41145D02*
X273220Y38270D01*
G01X277445Y60212D02*
Y40585D01*
G01X276095Y60772D02*
Y41145D01*
G01X237513Y37380D02*
Y23920D01*
G01X238863Y37940D02*
Y23920D01*
G01X236963Y37930D02*
X237513Y37380D01*
G01X237523Y39280D02*
X238863Y37940D01*
G01X234920Y37930D02*
X236963D01*
G01X235480Y39280D02*
X237523D01*
G01X233580Y39270D02*
X234920Y37930D01*
G01X234930Y39830D02*
X235480Y39280D01*
G01X233580Y41490D02*
Y39270D01*
G01X234930Y40930D02*
Y39830D01*
G01X234920Y42830D02*
X233580Y41490D01*
G01X235480Y41480D02*
X234930Y40930D01*
G01X237523Y41480D02*
X235480D01*
G01X238863Y42820D02*
X237523Y41480D01*
G01X238863Y37940D02*
Y23920D01*
G01X237513Y37380D02*
Y23920D01*
G01X237523Y39280D02*
X238863Y37940D01*
G01X236963Y37930D02*
X237513Y37380D01*
G01X235480Y39280D02*
X237523D01*
G01X234920Y37930D02*
X236963D01*
G01X234930Y39830D02*
X235480Y39280D01*
G01X233580Y39270D02*
X234920Y37930D01*
G01X234930Y40930D02*
Y39830D01*
G01X233580Y41490D02*
Y39270D01*
G01X235480Y41480D02*
X234930Y40930D01*
G01X234920Y42830D02*
X233580Y41490D01*
G01X237523Y41480D02*
X235480D01*
G01X238863Y42820D02*
X237523Y41480D01*
G01X253261Y31600D02*
Y23920D01*
G01X254611Y32160D02*
Y23920D01*
G01X246783Y38078D02*
X253261Y31600D01*
G01X247343Y39428D02*
X254611Y32160D01*
G01X245080Y38078D02*
X246783D01*
G01X245640Y39428D02*
X247343D01*
G01X243740Y39418D02*
X245080Y38078D01*
G01X245090Y39978D02*
X245640Y39428D01*
G01X243740Y41638D02*
Y39418D01*
G01X245090Y41078D02*
Y39978D01*
G01X245080Y42978D02*
X243740Y41638D01*
G01X245640Y41628D02*
X245090Y41078D01*
G01X247343Y41628D02*
X245640D01*
G01X248683Y42968D02*
X247343Y41628D01*
G01X254611Y32160D02*
Y23920D01*
G01X253261Y31600D02*
Y23920D01*
G01X247343Y39428D02*
X254611Y32160D01*
G01X246783Y38078D02*
X253261Y31600D01*
G01X245640Y39428D02*
X247343D01*
G01X245080Y38078D02*
X246783D01*
G01X245090Y39978D02*
X245640Y39428D01*
G01X243740Y39418D02*
X245080Y38078D01*
G01X245090Y41078D02*
Y39978D01*
G01X243740Y41638D02*
Y39418D01*
G01X245640Y41628D02*
X245090Y41078D01*
G01X245080Y42978D02*
X243740Y41638D01*
G01X247343Y41628D02*
X245640D01*
G01X248683Y42968D02*
X247343Y41628D01*
G01X255533Y63900D02*
X251433Y59800D01*
G01X256883Y63340D02*
X252783Y59240D01*
G01X255533Y67900D02*
Y63900D01*
G01X256883Y67340D02*
Y63340D01*
G01X259123Y71490D02*
X255533Y67900D01*
G01X260473Y70930D02*
X256883Y67340D01*
G01X259123Y75653D02*
Y71490D01*
G01X260473Y75093D02*
Y70930D01*
G01X262810Y79340D02*
X259123Y75653D01*
G01X263370Y77990D02*
X260473Y75093D01*
G01X264523Y79340D02*
X262810D01*
G01X265083Y77990D02*
X263370D01*
G01X267213Y82030D02*
X264523Y79340D01*
G01X268563Y81470D02*
X265083Y77990D01*
G01X267213Y86200D02*
Y82030D01*
G01X268563Y85640D02*
Y81470D01*
G01X268413Y87400D02*
X267213Y86200D01*
G01X269523Y86600D02*
X268563Y85640D01*
G01X256883Y63340D02*
X252783Y59240D01*
G01X255533Y63900D02*
X251433Y59800D01*
G01X256883Y67340D02*
Y63340D01*
G01X255533Y67900D02*
Y63900D01*
G01X260473Y70930D02*
X256883Y67340D01*
G01X259123Y71490D02*
X255533Y67900D01*
G01X260473Y75093D02*
Y70930D01*
G01X259123Y75653D02*
Y71490D01*
G01X263370Y77990D02*
X260473Y75093D01*
G01X262810Y79340D02*
X259123Y75653D01*
G01X265083Y77990D02*
X263370D01*
G01X264523Y79340D02*
X262810D01*
G01X268563Y81470D02*
X265083Y77990D01*
G01X267213Y82030D02*
X264523Y79340D01*
G01X268563Y85640D02*
Y81470D01*
G01X267213Y86200D02*
Y82030D01*
G01X269523Y86600D02*
X268563Y85640D01*
G01X268413Y87400D02*
X267213Y86200D01*
G01X278883Y63560D02*
X276095Y60772D01*
G01X280233Y63000D02*
X277445Y60212D01*
G01X278883Y67197D02*
Y63560D01*
G01X280233Y67757D02*
Y63000D01*
G01X274950Y71130D02*
X278883Y67197D01*
G01X276300Y71690D02*
X280233Y67757D01*
G01X274950Y75950D02*
Y71130D01*
G01X276300Y75390D02*
Y71690D01*
G01X278000Y79000D02*
X274950Y75950D01*
G01X278560Y77650D02*
X276300Y75390D01*
G01X281520Y79000D02*
X278000D01*
G01X282080Y77650D02*
X278560D01*
G01X282733Y80213D02*
X281520Y79000D01*
G01X284083Y79653D02*
X282080Y77650D01*
G01X282733Y86100D02*
Y80213D01*
G01X284083Y85540D02*
Y79653D01*
G01X284033Y87400D02*
X282733Y86100D01*
G01X285143Y86600D02*
X284083Y85540D01*
G01X280233Y63000D02*
X277445Y60212D01*
G01X278883Y63560D02*
X276095Y60772D01*
G01X280233Y67757D02*
Y63000D01*
G01X278883Y67197D02*
Y63560D01*
G01X276300Y71690D02*
X280233Y67757D01*
G01X274950Y71130D02*
X278883Y67197D01*
G01X276300Y75390D02*
Y71690D01*
G01X274950Y75950D02*
Y71130D01*
G01X278560Y77650D02*
X276300Y75390D01*
G01X278000Y79000D02*
X274950Y75950D01*
G01X282080Y77650D02*
X278560D01*
G01X281520Y79000D02*
X278000D01*
G01X284083Y79653D02*
X282080Y77650D01*
G01X282733Y80213D02*
X281520Y79000D01*
G01X284083Y85540D02*
Y79653D01*
G01X282733Y86100D02*
Y80213D01*
G01X285143Y86600D02*
X284083Y85540D01*
G01X284033Y87400D02*
X282733Y86100D01*
G01X236963Y42830D02*
X234920D01*
G01X237513Y43380D02*
X236963Y42830D01*
G01X237513Y44480D02*
Y43380D01*
G01X238863Y45040D02*
Y42820D01*
G01X236963Y45030D02*
X237513Y44480D01*
G01X237523Y46380D02*
X238863Y45040D01*
G01X234920Y45030D02*
X236963D01*
G01X235480Y46380D02*
X237523D01*
G01X233580Y46370D02*
X234920Y45030D01*
G01X234930Y46930D02*
X235480Y46380D01*
G01X233580Y48590D02*
Y46370D01*
G01X234930Y48030D02*
Y46930D01*
G01X234920Y49930D02*
X233580Y48590D01*
G01X235480Y48580D02*
X234930Y48030D01*
G01X236963Y49930D02*
X234920D01*
G01X237523Y48580D02*
X235480D01*
G01X237513Y50480D02*
X236963Y49930D01*
G01X238863Y49920D02*
X237523Y48580D01*
G01X237513Y51580D02*
Y50480D01*
G01X238863Y52140D02*
Y49920D01*
G01X236963Y52130D02*
X237513Y51580D01*
G01X237523Y53480D02*
X238863Y52140D01*
G01X235120Y52130D02*
X236963D01*
G01X235680Y53480D02*
X237523D01*
G01X233830Y53420D02*
X235120Y52130D01*
G01X235180Y53980D02*
X235680Y53480D01*
G01X233830Y55740D02*
Y53420D01*
G01X235180Y55180D02*
Y53980D01*
G01X235120Y57030D02*
X233830Y55740D01*
G01X235680Y55680D02*
X235180Y55180D01*
G01X236963Y57030D02*
X235120D01*
G01X237523Y55680D02*
X235680D01*
G01X239473Y59540D02*
X236963Y57030D01*
G01X240823Y58980D02*
X237523Y55680D01*
G01X239473Y67150D02*
Y59540D01*
G01X240823Y67710D02*
Y58980D01*
G01X235723Y70900D02*
X239473Y67150D01*
G01X237073Y71460D02*
X240823Y67710D01*
G01X235723Y86200D02*
Y70900D01*
G01X237073Y85640D02*
Y71460D01*
G01X236923Y87400D02*
X235723Y86200D01*
G01X238033Y86600D02*
X237073Y85640D01*
G01X236963Y42830D02*
X234920D01*
G01X237513Y43380D02*
X236963Y42830D01*
G01X238863Y45040D02*
Y42820D01*
G01X237513Y44480D02*
Y43380D01*
G01X237523Y46380D02*
X238863Y45040D01*
G01X236963Y45030D02*
X237513Y44480D01*
G01X235480Y46380D02*
X237523D01*
G01X234920Y45030D02*
X236963D01*
G01X234930Y46930D02*
X235480Y46380D01*
G01X233580Y46370D02*
X234920Y45030D01*
G01X234930Y48030D02*
Y46930D01*
G01X233580Y48590D02*
Y46370D01*
G01X235480Y48580D02*
X234930Y48030D01*
G01X234920Y49930D02*
X233580Y48590D01*
G01X237523Y48580D02*
X235480D01*
G01X236963Y49930D02*
X234920D01*
G01X238863Y49920D02*
X237523Y48580D01*
G01X237513Y50480D02*
X236963Y49930D01*
G01X238863Y52140D02*
Y49920D01*
G01X237513Y51580D02*
Y50480D01*
G01X237523Y53480D02*
X238863Y52140D01*
G01X236963Y52130D02*
X237513Y51580D01*
G01X235680Y53480D02*
X237523D01*
G01X235120Y52130D02*
X236963D01*
G01X235180Y53980D02*
X235680Y53480D01*
G01X233830Y53420D02*
X235120Y52130D01*
G01X235180Y55180D02*
Y53980D01*
G01X233830Y55740D02*
Y53420D01*
G01X235680Y55680D02*
X235180Y55180D01*
G01X235120Y57030D02*
X233830Y55740D01*
G01X237523Y55680D02*
X235680D01*
G01X236963Y57030D02*
X235120D01*
G01X240823Y58980D02*
X237523Y55680D01*
G01X239473Y59540D02*
X236963Y57030D01*
G01X240823Y67710D02*
Y58980D01*
G01X239473Y67150D02*
Y59540D01*
G01X237073Y71460D02*
X240823Y67710D01*
G01X235723Y70900D02*
X239473Y67150D01*
G01X237073Y85640D02*
Y71460D01*
G01X235723Y86200D02*
Y70900D01*
G01X238033Y86600D02*
X237073Y85640D01*
G01X236923Y87400D02*
X235723Y86200D01*
G01X246783Y42978D02*
X245080D01*
G01X247333Y43528D02*
X246783Y42978D01*
G01X247333Y44628D02*
Y43528D01*
G01X248683Y45188D02*
Y42968D01*
G01X246783Y45178D02*
X247333Y44628D01*
G01X247343Y46528D02*
X248683Y45188D01*
G01X245080Y45178D02*
X246783D01*
G01X245640Y46528D02*
X247343D01*
G01X243740Y46518D02*
X245080Y45178D01*
G01X245090Y47078D02*
X245640Y46528D01*
G01X243740Y48738D02*
Y46518D01*
G01X245090Y48178D02*
Y47078D01*
G01X245080Y50078D02*
X243740Y48738D01*
G01X245640Y48728D02*
X245090Y48178D01*
G01X246783Y50078D02*
X245080D01*
G01X247343Y48728D02*
X245640D01*
G01X247333Y50628D02*
X246783Y50078D01*
G01X248683Y50068D02*
X247343Y48728D01*
G01X247333Y51728D02*
Y50628D01*
G01X248683Y52288D02*
Y50068D01*
G01X246783Y52278D02*
X247333Y51728D01*
G01X247343Y53628D02*
X248683Y52288D01*
G01X244930Y52278D02*
X246783D01*
G01X245490Y53628D02*
X247343D01*
G01X243640Y53568D02*
X244930Y52278D01*
G01X244990Y54128D02*
X245490Y53628D01*
G01X243640Y55888D02*
Y53568D01*
G01X244990Y55328D02*
Y54128D01*
G01X244930Y57178D02*
X243640Y55888D01*
G01X245490Y55828D02*
X244990Y55328D01*
G01X246783Y57178D02*
X244930D01*
G01X247343Y55828D02*
X245490D01*
G01X247333Y57728D02*
X246783Y57178D01*
G01X248683Y57168D02*
X247343Y55828D01*
G01X247333Y68000D02*
Y57728D01*
G01X248683Y67440D02*
Y57168D01*
G01X251468Y72135D02*
X247333Y68000D01*
G01X252818Y71575D02*
X248683Y67440D01*
G01X251468Y86200D02*
Y72135D01*
G01X252818Y85640D02*
Y71575D01*
G01X252668Y87400D02*
X251468Y86200D01*
G01X253778Y86600D02*
X252818Y85640D01*
G01X246783Y42978D02*
X245080D01*
G01X247333Y43528D02*
X246783Y42978D01*
G01X248683Y45188D02*
Y42968D01*
G01X247333Y44628D02*
Y43528D01*
G01X247343Y46528D02*
X248683Y45188D01*
G01X246783Y45178D02*
X247333Y44628D01*
G01X245640Y46528D02*
X247343D01*
G01X245080Y45178D02*
X246783D01*
G01X245090Y47078D02*
X245640Y46528D01*
G01X243740Y46518D02*
X245080Y45178D01*
G01X245090Y48178D02*
Y47078D01*
G01X243740Y48738D02*
Y46518D01*
G01X245640Y48728D02*
X245090Y48178D01*
G01X245080Y50078D02*
X243740Y48738D01*
G01X247343Y48728D02*
X245640D01*
G01X246783Y50078D02*
X245080D01*
G01X248683Y50068D02*
X247343Y48728D01*
G01X247333Y50628D02*
X246783Y50078D01*
G01X248683Y52288D02*
Y50068D01*
G01X247333Y51728D02*
Y50628D01*
G01X247343Y53628D02*
X248683Y52288D01*
G01X246783Y52278D02*
X247333Y51728D01*
G01X245490Y53628D02*
X247343D01*
G01X244930Y52278D02*
X246783D01*
G01X244990Y54128D02*
X245490Y53628D01*
G01X243640Y53568D02*
X244930Y52278D01*
G01X244990Y55328D02*
Y54128D01*
G01X243640Y55888D02*
Y53568D01*
G01X245490Y55828D02*
X244990Y55328D01*
G01X244930Y57178D02*
X243640Y55888D01*
G01X247343Y55828D02*
X245490D01*
G01X246783Y57178D02*
X244930D01*
G01X248683Y57168D02*
X247343Y55828D01*
G01X247333Y57728D02*
X246783Y57178D01*
G01X248683Y67440D02*
Y57168D01*
G01X247333Y68000D02*
Y57728D01*
G01X252818Y71575D02*
X248683Y67440D01*
G01X251468Y72135D02*
X247333Y68000D01*
G01X252818Y85640D02*
Y71575D01*
G01X251468Y86200D02*
Y72135D01*
G01X253778Y86600D02*
X252818Y85640D01*
G01X252668Y87400D02*
X251468Y86200D01*
G01X316254Y32739D02*
Y23920D01*
G01X317604Y33299D02*
Y23920D01*
G01X312243Y36750D02*
X316254Y32739D01*
G01X312803Y38100D02*
X317604Y33299D01*
G01X308373Y36750D02*
X312243D01*
G01X308933Y38100D02*
X312803D01*
G01X303983Y41140D02*
X308373Y36750D01*
G01X305333Y41700D02*
X308933Y38100D01*
G01X303983Y61660D02*
Y41140D01*
G01X305333Y61100D02*
Y41700D01*
G01X317604Y33299D02*
Y23920D01*
G01X316254Y32739D02*
Y23920D01*
G01X312803Y38100D02*
X317604Y33299D01*
G01X312243Y36750D02*
X316254Y32739D01*
G01X308933Y38100D02*
X312803D01*
G01X308373Y36750D02*
X312243D01*
G01X305333Y41700D02*
X308933Y38100D01*
G01X303983Y41140D02*
X308373Y36750D01*
G01X305333Y61100D02*
Y41700D01*
G01X303983Y61660D02*
Y41140D01*
G01X314333Y72010D02*
X303983Y61660D01*
G01X315683Y71450D02*
X305333Y61100D01*
G01X314333Y85800D02*
Y72010D01*
G01X315683Y85240D02*
Y71450D01*
G01X316073Y87540D02*
X314333Y85800D01*
G01X317283Y86840D02*
X315683Y85240D01*
G01Y71450D02*
X305333Y61100D01*
G01X314333Y72010D02*
X303983Y61660D01*
G01X315683Y85240D02*
Y71450D01*
G01X314333Y85800D02*
Y72010D01*
G01X317283Y86840D02*
X315683Y85240D01*
G01X316073Y87540D02*
X314333Y85800D01*
M02*
